FILE_TYPE = MACRO_DRAWING;
SET COLOR_WIRE YELLOW;
SET COLOR_PROP ORANGE;
SET COLOR_DOT WHITE;
SET COLOR_ARC YELLOW;
SET COLOR_BODY GREEN;
SET COLOR_NOTE PURPLE;
SET PROP_DISPLAY VALUE;
SET PAGE_NUMBER P90;
FORCEADD GND..1
(-2225 2175);
FORCEPROP 3 LASTPIN (-2225 2225) SIG_NAME GND\g
J 0
(-2215 2235);
DISPLAY 0.659574 (-2215 2235);
PAINT MONO (-2215 2235);
DISPLAY INVISIBLE (-2215 2235);
FORCEPROP 1 LAST VOLTAGE 0.0
J 0
(-2270 2132);
DISPLAY 0.723404 (-2270 2132);
PAINT SKYBLUE (-2270 2132);
DISPLAY INVISIBLE (-2270 2132);
FORCEPROP 2 LAST CDS_LIB mstr_symbols
J 0
(-2225 2175);
DISPLAY 0.723404 (-2225 2175);
DISPLAY INVISIBLE (-2225 2175);
FORCEPROP 1 LAST SIZE 1B
J 0
(-2150 2125);
DISPLAY 0.851064 (-2150 2125);
PAINT GREEN (-2150 2125);
DISPLAY INVISIBLE (-2150 2125);
FORCEPROP 1 LAST BODY_TYPE PLUMBING
J 0
(-2270 2132);
DISPLAY 0.340426 (-2270 2132);
PAINT GREEN (-2270 2132);
DISPLAY INVISIBLE (-2270 2132);
FORCEPROP 1 LAST HDL_POWER GND
J 0
(-2225 2325);
DISPLAY 0.851064 (-2225 2325);
PAINT GREEN (-2225 2325);
DISPLAY INVISIBLE (-2225 2325);
FORCEPROP 1 LAST PATH I150
J 0
(-2150 2175);
DISPLAY 0.872340 (-2150 2175);
PAINT GREEN (-2150 2175);
DISPLAY INVISIBLE (-2150 2175);
FORCEADD GND..1
(-425 1950);
FORCEPROP 3 LASTPIN (-425 2000) SIG_NAME GND\g
J 0
(-415 2010);
DISPLAY 0.659574 (-415 2010);
PAINT MONO (-415 2010);
DISPLAY INVISIBLE (-415 2010);
FORCEPROP 1 LAST VOLTAGE 0.0
J 0
(-470 1907);
DISPLAY 0.723404 (-470 1907);
PAINT SKYBLUE (-470 1907);
DISPLAY INVISIBLE (-470 1907);
FORCEPROP 1 LAST SIZE 1B
J 0
(-350 1900);
DISPLAY 0.851064 (-350 1900);
PAINT GREEN (-350 1900);
DISPLAY INVISIBLE (-350 1900);
FORCEPROP 2 LAST CDS_LIB mstr_symbols
J 0
(-425 1950);
DISPLAY 0.723404 (-425 1950);
DISPLAY INVISIBLE (-425 1950);
FORCEPROP 1 LAST BODY_TYPE PLUMBING
J 0
(-470 1907);
DISPLAY 0.340426 (-470 1907);
PAINT GREEN (-470 1907);
DISPLAY INVISIBLE (-470 1907);
FORCEPROP 1 LAST HDL_POWER GND
J 0
(-425 2100);
DISPLAY 0.851064 (-425 2100);
PAINT GREEN (-425 2100);
DISPLAY INVISIBLE (-425 2100);
FORCEPROP 1 LAST PATH I152
J 0
(-350 1950);
DISPLAY 0.872340 (-350 1950);
PAINT GREEN (-350 1950);
DISPLAY INVISIBLE (-350 1950);
FORCEADD OFFPAGE..5
(-8375 2275);
FORCEPROP 2 LAST $XR0 15 
J 0
(-8629 2275);
DISPLAY 0.638298 (-8629 2275);
PAINT MONO (-8629 2275);
FORCEPROP 2 LAST CDS_LIB mstr_standard
J 0
(-8375 2275);
DISPLAY 0.808511 (-8375 2275);
DISPLAY INVISIBLE (-8375 2275);
FORCEPROP 1 LAST OFFPAGE TRUE
J 0
(-8050 2150);
DISPLAY 0.872340 (-8050 2150);
PAINT GREEN (-8050 2150);
DISPLAY INVISIBLE (-8050 2150);
FORCEPROP 1 LAST COMMENT_BODY TRUE
J 0
(-8275 2200);
DISPLAY 0.872340 (-8275 2200);
PAINT GREEN (-8275 2200);
DISPLAY INVISIBLE (-8275 2200);
FORCEPROP 2 LAST PATH I167
J 0
(-8325 2350);
DISPLAY 0.808511 (-8325 2350);
DISPLAY INVISIBLE (-8325 2350);
FORCEADD OFFPAGE..5
(-8375 2325);
FORCEPROP 2 LAST $XR0 15 
J 0
(-8629 2325);
DISPLAY 0.638298 (-8629 2325);
PAINT MONO (-8629 2325);
FORCEPROP 2 LAST CDS_LIB mstr_standard
J 0
(-8375 2325);
DISPLAY 0.808511 (-8375 2325);
DISPLAY INVISIBLE (-8375 2325);
FORCEPROP 1 LAST OFFPAGE TRUE
J 0
(-8050 2200);
DISPLAY 0.872340 (-8050 2200);
PAINT GREEN (-8050 2200);
DISPLAY INVISIBLE (-8050 2200);
FORCEPROP 1 LAST COMMENT_BODY TRUE
J 0
(-8275 2250);
DISPLAY 0.872340 (-8275 2250);
PAINT GREEN (-8275 2250);
DISPLAY INVISIBLE (-8275 2250);
FORCEPROP 2 LAST PATH I168
J 0
(-8325 2400);
DISPLAY 0.808511 (-8325 2400);
DISPLAY INVISIBLE (-8325 2400);
FORCEADD VCC_CORE..1
(-8550 3775);
FORCEPROP 3 LASTPIN (-8550 3725) SIG_NAME P3V3_AUX\g
J 0
(-8540 3735);
DISPLAY 0.659574 (-8540 3735);
PAINT MONO (-8540 3735);
DISPLAY INVISIBLE (-8540 3735);
FORCEPROP 1 LAST HDL_POWER P3V3_AUX
J 1
(-8550 3825);
DISPLAY 0.489362 (-8550 3825);
PAINT GREEN (-8550 3825);
FORCEPROP 2 LAST ROOM PVCCINFAON_CPU0_CTRL
J 0
(-8550 3875);
DISPLAY 0.808511 (-8550 3875);
PAINT RED (-8550 3875);
DISPLAY INVISIBLE (-8550 3875);
FORCEPROP 0 LAST VOLTAGE 3.3
J 0
(-8825 3925);
DISPLAY 1.021277 (-8825 3925);
PAINT SKYBLUE (-8825 3925);
DISPLAY INVISIBLE (-8825 3925);
FORCEPROP 2 LAST CDS_LIB mstr_symbols
J 0
(-8550 3775);
PAINT MONO (-8550 3775);
DISPLAY INVISIBLE (-8550 3775);
FORCEPROP 1 LAST PATH I175
J 0
(-8500 3800);
DISPLAY 0.872340 (-8500 3800);
PAINT GREEN (-8500 3800);
DISPLAY INVISIBLE (-8500 3800);
FORCEADD OFFPAGE..1
(-8175 3425);
FORCEPROP 2 LAST $XR0 15 
J 0
(-8396 3425);
DISPLAY 0.638298 (-8396 3425);
PAINT MONO (-8396 3425);
FORCEPROP 2 LAST CDS_LIB mstr_standard
J 0
(-8175 3425);
DISPLAY 0.808511 (-8175 3425);
DISPLAY INVISIBLE (-8175 3425);
FORCEPROP 1 LAST OFFPAGE TRUE
J 0
(-7850 3300);
DISPLAY 0.872340 (-7850 3300);
PAINT GREEN (-7850 3300);
DISPLAY INVISIBLE (-7850 3300);
FORCEPROP 1 LAST COMMENT_BODY TRUE
J 0
(-8050 3325);
DISPLAY 0.872340 (-8050 3325);
PAINT GREEN (-8050 3325);
DISPLAY INVISIBLE (-8050 3325);
FORCEPROP 2 LAST PATH I176
J 0
(-8375 3650);
DISPLAY 0.808511 (-8375 3650);
DISPLAY INVISIBLE (-8375 3650);
FORCEADD TAP..1
R 2
(-7775 3525);
FORCEPROP 3 LASTPIN (-7725 3525) SIG_NAME M_F_CPU0_SB_CB<0>
J 0
(-7715 3535);
DISPLAY 0.659574 (-7715 3535);
PAINT MONO (-7715 3535);
DISPLAY INVISIBLE (-7715 3535);
FORCEPROP 1 LASTPIN (-7725 3525) BN 0
J 2
(-7713 3533);
DISPLAY 0.489362 (-7713 3533);
PAINT GREEN (-7713 3533);
FORCEPROP 2 LAST CDS_LIB mstr_standard
J 0
(-7775 3525);
DISPLAY 0.723404 (-7775 3525);
PAINT MONO (-7775 3525);
DISPLAY INVISIBLE (-7775 3525);
FORCEPROP 1 LAST BODY_TYPE PLUMBING
J 2
(-7775 3575);
DISPLAY 0.872340 (-7775 3575);
PAINT GREEN (-7775 3575);
DISPLAY INVISIBLE (-7775 3575);
FORCEPROP 1 LAST HDL_TAP TRUE
J 2
(-8100 3400);
DISPLAY 0.872340 (-8100 3400);
DISPLAY INVISIBLE (-8100 3400);
FORCEPROP 1 LAST PATH I177
J 2
(-7773 3525);
DISPLAY 0.872340 (-7773 3525);
PAINT GREEN (-7773 3525);
DISPLAY INVISIBLE (-7773 3525);
FORCEADD TAP..1
R 2
(-7775 3575);
FORCEPROP 3 LASTPIN (-7725 3575) SIG_NAME M_F_CPU0_SB_CB<1>
J 0
(-7715 3585);
DISPLAY 0.659574 (-7715 3585);
PAINT MONO (-7715 3585);
DISPLAY INVISIBLE (-7715 3585);
FORCEPROP 1 LASTPIN (-7725 3575) BN 1
J 2
(-7713 3583);
DISPLAY 0.489362 (-7713 3583);
PAINT GREEN (-7713 3583);
FORCEPROP 2 LAST CDS_LIB mstr_standard
J 0
(-7775 3575);
DISPLAY 0.723404 (-7775 3575);
PAINT MONO (-7775 3575);
DISPLAY INVISIBLE (-7775 3575);
FORCEPROP 1 LAST BODY_TYPE PLUMBING
J 2
(-7775 3625);
DISPLAY 0.872340 (-7775 3625);
PAINT GREEN (-7775 3625);
DISPLAY INVISIBLE (-7775 3625);
FORCEPROP 1 LAST HDL_TAP TRUE
J 2
(-8100 3450);
DISPLAY 0.872340 (-8100 3450);
DISPLAY INVISIBLE (-8100 3450);
FORCEPROP 1 LAST PATH I178
J 2
(-7773 3575);
DISPLAY 0.872340 (-7773 3575);
PAINT GREEN (-7773 3575);
DISPLAY INVISIBLE (-7773 3575);
FORCEADD TAP..1
R 2
(-7775 3625);
FORCEPROP 3 LASTPIN (-7725 3625) SIG_NAME M_F_CPU0_SB_CB<2>
J 0
(-7715 3635);
DISPLAY 0.659574 (-7715 3635);
PAINT MONO (-7715 3635);
DISPLAY INVISIBLE (-7715 3635);
FORCEPROP 1 LASTPIN (-7725 3625) BN 2
J 2
(-7713 3633);
DISPLAY 0.489362 (-7713 3633);
PAINT GREEN (-7713 3633);
FORCEPROP 2 LAST CDS_LIB mstr_standard
J 0
(-7775 3625);
DISPLAY 0.723404 (-7775 3625);
PAINT MONO (-7775 3625);
DISPLAY INVISIBLE (-7775 3625);
FORCEPROP 1 LAST BODY_TYPE PLUMBING
J 2
(-7775 3675);
DISPLAY 0.872340 (-7775 3675);
PAINT GREEN (-7775 3675);
DISPLAY INVISIBLE (-7775 3675);
FORCEPROP 1 LAST HDL_TAP TRUE
J 2
(-8100 3500);
DISPLAY 0.872340 (-8100 3500);
DISPLAY INVISIBLE (-8100 3500);
FORCEPROP 1 LAST PATH I179
J 2
(-7773 3625);
DISPLAY 0.872340 (-7773 3625);
PAINT GREEN (-7773 3625);
DISPLAY INVISIBLE (-7773 3625);
FORCEADD OFFPAGE..6
(-8375 3925);
FORCEPROP 2 LAST $XR0 15 
J 0
(-8654 3925);
DISPLAY 0.638298 (-8654 3925);
PAINT MONO (-8654 3925);
FORCEPROP 2 LAST CDS_LIB mstr_standard
J 0
(-8375 3925);
DISPLAY 0.723404 (-8375 3925);
PAINT MONO (-8375 3925);
DISPLAY INVISIBLE (-8375 3925);
FORCEPROP 1 LAST OFFPAGE TRUE
J 0
(-8050 3800);
DISPLAY 0.872340 (-8050 3800);
PAINT GREEN (-8050 3800);
DISPLAY INVISIBLE (-8050 3800);
FORCEPROP 1 LAST COMMENT_BODY TRUE
J 0
(-8275 3850);
DISPLAY 0.872340 (-8275 3850);
PAINT GREEN (-8275 3850);
DISPLAY INVISIBLE (-8275 3850);
FORCEPROP 2 LAST PATH I180
J 0
(-8325 4000);
DISPLAY 0.808511 (-8325 4000);
DISPLAY INVISIBLE (-8325 4000);
FORCEADD OFFPAGE..6
(-8375 4375);
FORCEPROP 2 LAST $XR0 15 
J 0
(-8654 4375);
DISPLAY 0.638298 (-8654 4375);
PAINT MONO (-8654 4375);
FORCEPROP 2 LAST CDS_LIB mstr_standard
J 0
(-8375 4375);
DISPLAY 0.723404 (-8375 4375);
PAINT MONO (-8375 4375);
DISPLAY INVISIBLE (-8375 4375);
FORCEPROP 1 LAST OFFPAGE TRUE
J 0
(-8050 4250);
DISPLAY 0.872340 (-8050 4250);
PAINT GREEN (-8050 4250);
DISPLAY INVISIBLE (-8050 4250);
FORCEPROP 1 LAST COMMENT_BODY TRUE
J 0
(-8275 4300);
DISPLAY 0.872340 (-8275 4300);
PAINT GREEN (-8275 4300);
DISPLAY INVISIBLE (-8275 4300);
FORCEPROP 2 LAST PATH I181
J 0
(-8325 4450);
DISPLAY 0.808511 (-8325 4450);
DISPLAY INVISIBLE (-8325 4450);
FORCEADD OFFPAGE..1
(-8375 4575);
FORCEPROP 2 LAST $XR0 15 
J 0
(-8626 4575);
DISPLAY 0.638298 (-8626 4575);
PAINT MONO (-8626 4575);
FORCEPROP 2 LAST CDS_LIB mstr_standard
J 0
(-8375 4575);
DISPLAY 0.808511 (-8375 4575);
DISPLAY INVISIBLE (-8375 4575);
FORCEPROP 1 LAST OFFPAGE TRUE
J 0
(-8050 4450);
DISPLAY 0.872340 (-8050 4450);
PAINT GREEN (-8050 4450);
DISPLAY INVISIBLE (-8050 4450);
FORCEPROP 1 LAST COMMENT_BODY TRUE
J 0
(-8250 4475);
DISPLAY 0.872340 (-8250 4475);
PAINT GREEN (-8250 4475);
DISPLAY INVISIBLE (-8250 4475);
FORCEPROP 2 LAST PATH I182
J 0
(-8325 4650);
DISPLAY 0.808511 (-8325 4650);
DISPLAY INVISIBLE (-8325 4650);
FORCEADD OFFPAGE..1
(-8375 4475);
FORCEPROP 2 LAST $XR0 15 
J 0
(-8626 4475);
DISPLAY 0.638298 (-8626 4475);
PAINT MONO (-8626 4475);
FORCEPROP 2 LAST CDS_LIB mstr_standard
J 0
(-8375 4475);
DISPLAY 0.723404 (-8375 4475);
PAINT MONO (-8375 4475);
DISPLAY INVISIBLE (-8375 4475);
FORCEPROP 1 LAST OFFPAGE TRUE
J 0
(-8050 4350);
DISPLAY 0.872340 (-8050 4350);
PAINT GREEN (-8050 4350);
DISPLAY INVISIBLE (-8050 4350);
FORCEPROP 1 LAST COMMENT_BODY TRUE
J 0
(-8250 4375);
DISPLAY 0.872340 (-8250 4375);
PAINT GREEN (-8250 4375);
DISPLAY INVISIBLE (-8250 4375);
FORCEPROP 2 LAST PATH I183
J 0
(-8325 4550);
DISPLAY 0.808511 (-8325 4550);
DISPLAY INVISIBLE (-8325 4550);
FORCEADD OFFPAGE..1
(-8375 4425);
FORCEPROP 2 LAST $XR0 15 
J 0
(-8626 4425);
DISPLAY 0.638298 (-8626 4425);
PAINT MONO (-8626 4425);
FORCEPROP 2 LAST CDS_LIB mstr_standard
J 0
(-8375 4425);
DISPLAY 0.808511 (-8375 4425);
DISPLAY INVISIBLE (-8375 4425);
FORCEPROP 1 LAST OFFPAGE TRUE
J 0
(-8050 4300);
DISPLAY 0.872340 (-8050 4300);
PAINT GREEN (-8050 4300);
DISPLAY INVISIBLE (-8050 4300);
FORCEPROP 1 LAST COMMENT_BODY TRUE
J 0
(-8250 4325);
DISPLAY 0.872340 (-8250 4325);
PAINT GREEN (-8250 4325);
DISPLAY INVISIBLE (-8250 4325);
FORCEPROP 2 LAST PATH I184
J 0
(-8325 4500);
DISPLAY 0.808511 (-8325 4500);
DISPLAY INVISIBLE (-8325 4500);
FORCEADD OFFPAGE..1
(-8375 4625);
FORCEPROP 2 LAST $XR0 15 
J 0
(-8626 4625);
DISPLAY 0.638298 (-8626 4625);
PAINT MONO (-8626 4625);
FORCEPROP 2 LAST CDS_LIB mstr_standard
J 0
(-8375 4625);
DISPLAY 0.723404 (-8375 4625);
PAINT MONO (-8375 4625);
DISPLAY INVISIBLE (-8375 4625);
FORCEPROP 1 LAST OFFPAGE TRUE
J 0
(-8050 4500);
DISPLAY 0.872340 (-8050 4500);
PAINT GREEN (-8050 4500);
DISPLAY INVISIBLE (-8050 4500);
FORCEPROP 1 LAST COMMENT_BODY TRUE
J 0
(-8250 4525);
DISPLAY 0.872340 (-8250 4525);
PAINT GREEN (-8250 4525);
DISPLAY INVISIBLE (-8250 4525);
FORCEPROP 2 LAST PATH I185
J 0
(-8325 4700);
DISPLAY 0.808511 (-8325 4700);
DISPLAY INVISIBLE (-8325 4700);
FORCEADD OFFPAGE..1
(-8375 4875);
FORCEPROP 2 LAST $XR0 15 
J 0
(-8626 4875);
DISPLAY 0.638298 (-8626 4875);
PAINT MONO (-8626 4875);
FORCEPROP 2 LAST CDS_LIB mstr_standard
J 0
(-8375 4875);
DISPLAY 0.808511 (-8375 4875);
DISPLAY INVISIBLE (-8375 4875);
FORCEPROP 1 LAST OFFPAGE TRUE
J 0
(-8050 4750);
DISPLAY 0.872340 (-8050 4750);
PAINT GREEN (-8050 4750);
DISPLAY INVISIBLE (-8050 4750);
FORCEPROP 1 LAST COMMENT_BODY TRUE
J 0
(-8250 4775);
DISPLAY 0.872340 (-8250 4775);
PAINT GREEN (-8250 4775);
DISPLAY INVISIBLE (-8250 4775);
FORCEPROP 2 LAST PATH I186
J 0
(-8325 4950);
DISPLAY 0.808511 (-8325 4950);
DISPLAY INVISIBLE (-8325 4950);
FORCEADD OFFPAGE..1
(-8375 4775);
FORCEPROP 2 LAST $XR0 15 
J 0
(-8626 4775);
DISPLAY 0.638298 (-8626 4775);
PAINT MONO (-8626 4775);
FORCEPROP 2 LAST CDS_LIB mstr_standard
J 0
(-8375 4775);
DISPLAY 0.723404 (-8375 4775);
PAINT MONO (-8375 4775);
DISPLAY INVISIBLE (-8375 4775);
FORCEPROP 1 LAST OFFPAGE TRUE
J 0
(-8050 4650);
DISPLAY 0.872340 (-8050 4650);
PAINT GREEN (-8050 4650);
DISPLAY INVISIBLE (-8050 4650);
FORCEPROP 1 LAST COMMENT_BODY TRUE
J 0
(-8250 4675);
DISPLAY 0.872340 (-8250 4675);
PAINT GREEN (-8250 4675);
DISPLAY INVISIBLE (-8250 4675);
FORCEPROP 2 LAST PATH I187
J 0
(-8325 4850);
DISPLAY 0.808511 (-8325 4850);
DISPLAY INVISIBLE (-8325 4850);
FORCEADD OFFPAGE..1
(-8375 4725);
FORCEPROP 2 LAST $XR0 15 
J 0
(-8626 4725);
DISPLAY 0.638298 (-8626 4725);
PAINT MONO (-8626 4725);
FORCEPROP 2 LAST CDS_LIB mstr_standard
J 0
(-8375 4725);
DISPLAY 0.808511 (-8375 4725);
DISPLAY INVISIBLE (-8375 4725);
FORCEPROP 1 LAST OFFPAGE TRUE
J 0
(-8050 4600);
DISPLAY 0.872340 (-8050 4600);
PAINT GREEN (-8050 4600);
DISPLAY INVISIBLE (-8050 4600);
FORCEPROP 1 LAST COMMENT_BODY TRUE
J 0
(-8250 4625);
DISPLAY 0.872340 (-8250 4625);
PAINT GREEN (-8250 4625);
DISPLAY INVISIBLE (-8250 4625);
FORCEPROP 2 LAST PATH I188
J 0
(-8325 4800);
DISPLAY 0.808511 (-8325 4800);
DISPLAY INVISIBLE (-8325 4800);
FORCEADD OFFPAGE..1
(-8375 4925);
FORCEPROP 2 LAST $XR0 15 
J 0
(-8626 4925);
DISPLAY 0.638298 (-8626 4925);
PAINT MONO (-8626 4925);
FORCEPROP 2 LAST CDS_LIB mstr_standard
J 0
(-8375 4925);
DISPLAY 0.723404 (-8375 4925);
PAINT MONO (-8375 4925);
DISPLAY INVISIBLE (-8375 4925);
FORCEPROP 1 LAST OFFPAGE TRUE
J 0
(-8050 4800);
DISPLAY 0.872340 (-8050 4800);
PAINT GREEN (-8050 4800);
DISPLAY INVISIBLE (-8050 4800);
FORCEPROP 1 LAST COMMENT_BODY TRUE
J 0
(-8250 4825);
DISPLAY 0.872340 (-8250 4825);
PAINT GREEN (-8250 4825);
DISPLAY INVISIBLE (-8250 4825);
FORCEPROP 2 LAST PATH I189
J 0
(-8325 5000);
DISPLAY 0.808511 (-8325 5000);
DISPLAY INVISIBLE (-8325 5000);
FORCEADD OFFPAGE..1
(-8375 5375);
FORCEPROP 2 LAST $XR0 15 
J 0
(-8626 5375);
DISPLAY 0.638298 (-8626 5375);
PAINT MONO (-8626 5375);
FORCEPROP 2 LAST CDS_LIB mstr_standard
J 0
(-8375 5375);
DISPLAY 0.723404 (-8375 5375);
PAINT MONO (-8375 5375);
DISPLAY INVISIBLE (-8375 5375);
FORCEPROP 1 LAST OFFPAGE TRUE
J 0
(-8050 5250);
DISPLAY 0.872340 (-8050 5250);
PAINT GREEN (-8050 5250);
DISPLAY INVISIBLE (-8050 5250);
FORCEPROP 1 LAST COMMENT_BODY TRUE
J 0
(-8250 5275);
DISPLAY 0.872340 (-8250 5275);
PAINT GREEN (-8250 5275);
DISPLAY INVISIBLE (-8250 5275);
FORCEPROP 2 LAST PATH I190
J 0
(-8325 5450);
DISPLAY 0.808511 (-8325 5450);
DISPLAY INVISIBLE (-8325 5450);
FORCEADD OFFPAGE..1
(-8375 5775);
FORCEPROP 2 LAST $XR0 15 
J 0
(-8626 5775);
DISPLAY 0.638298 (-8626 5775);
PAINT MONO (-8626 5775);
FORCEPROP 2 LAST CDS_LIB mstr_standard
J 0
(-8375 5775);
DISPLAY 0.723404 (-8375 5775);
PAINT MONO (-8375 5775);
DISPLAY INVISIBLE (-8375 5775);
FORCEPROP 1 LAST OFFPAGE TRUE
J 0
(-8050 5650);
DISPLAY 0.872340 (-8050 5650);
PAINT GREEN (-8050 5650);
DISPLAY INVISIBLE (-8050 5650);
FORCEPROP 1 LAST COMMENT_BODY TRUE
J 0
(-8250 5675);
DISPLAY 0.872340 (-8250 5675);
PAINT GREEN (-8250 5675);
DISPLAY INVISIBLE (-8250 5675);
FORCEPROP 2 LAST PATH I191
J 0
(-8325 5850);
DISPLAY 0.808511 (-8325 5850);
DISPLAY INVISIBLE (-8325 5850);
FORCEADD TAP..1
R 2
(-7775 3725);
FORCEPROP 3 LASTPIN (-7725 3725) SIG_NAME M_F_CPU0_SB_CB<4>
J 0
(-7715 3735);
DISPLAY 0.659574 (-7715 3735);
PAINT MONO (-7715 3735);
DISPLAY INVISIBLE (-7715 3735);
FORCEPROP 1 LASTPIN (-7725 3725) BN 4
J 2
(-7713 3733);
DISPLAY 0.489362 (-7713 3733);
PAINT GREEN (-7713 3733);
FORCEPROP 2 LAST CDS_LIB mstr_standard
J 0
(-7775 3725);
DISPLAY 0.723404 (-7775 3725);
PAINT MONO (-7775 3725);
DISPLAY INVISIBLE (-7775 3725);
FORCEPROP 1 LAST BODY_TYPE PLUMBING
J 2
(-7775 3775);
DISPLAY 0.872340 (-7775 3775);
PAINT GREEN (-7775 3775);
DISPLAY INVISIBLE (-7775 3775);
FORCEPROP 1 LAST HDL_TAP TRUE
J 2
(-8100 3600);
DISPLAY 0.872340 (-8100 3600);
DISPLAY INVISIBLE (-8100 3600);
FORCEPROP 1 LAST PATH I192
J 2
(-7773 3725);
DISPLAY 0.872340 (-7773 3725);
PAINT GREEN (-7773 3725);
DISPLAY INVISIBLE (-7773 3725);
FORCEADD TAP..1
R 2
(-7775 3675);
FORCEPROP 3 LASTPIN (-7725 3675) SIG_NAME M_F_CPU0_SB_CB<3>
J 0
(-7715 3685);
DISPLAY 0.659574 (-7715 3685);
PAINT MONO (-7715 3685);
DISPLAY INVISIBLE (-7715 3685);
FORCEPROP 1 LASTPIN (-7725 3675) BN 3
J 2
(-7713 3683);
DISPLAY 0.489362 (-7713 3683);
PAINT GREEN (-7713 3683);
FORCEPROP 2 LAST CDS_LIB mstr_standard
J 0
(-7775 3675);
DISPLAY 0.723404 (-7775 3675);
PAINT MONO (-7775 3675);
DISPLAY INVISIBLE (-7775 3675);
FORCEPROP 1 LAST BODY_TYPE PLUMBING
J 2
(-7775 3725);
DISPLAY 0.872340 (-7775 3725);
PAINT GREEN (-7775 3725);
DISPLAY INVISIBLE (-7775 3725);
FORCEPROP 1 LAST HDL_TAP TRUE
J 2
(-8100 3550);
DISPLAY 0.872340 (-8100 3550);
DISPLAY INVISIBLE (-8100 3550);
FORCEPROP 1 LAST PATH I193
J 2
(-7773 3675);
DISPLAY 0.872340 (-7773 3675);
PAINT GREEN (-7773 3675);
DISPLAY INVISIBLE (-7773 3675);
FORCEADD TAP..1
R 2
(-7775 3775);
FORCEPROP 3 LASTPIN (-7725 3775) SIG_NAME M_F_CPU0_SB_CB<5>
J 0
(-7715 3785);
DISPLAY 0.659574 (-7715 3785);
PAINT MONO (-7715 3785);
DISPLAY INVISIBLE (-7715 3785);
FORCEPROP 1 LASTPIN (-7725 3775) BN 5
J 2
(-7713 3783);
DISPLAY 0.489362 (-7713 3783);
PAINT GREEN (-7713 3783);
FORCEPROP 2 LAST CDS_LIB mstr_standard
J 0
(-7775 3775);
DISPLAY 0.723404 (-7775 3775);
PAINT MONO (-7775 3775);
DISPLAY INVISIBLE (-7775 3775);
FORCEPROP 1 LAST BODY_TYPE PLUMBING
J 2
(-7775 3825);
DISPLAY 0.872340 (-7775 3825);
PAINT GREEN (-7775 3825);
DISPLAY INVISIBLE (-7775 3825);
FORCEPROP 1 LAST HDL_TAP TRUE
J 2
(-8100 3650);
DISPLAY 0.872340 (-8100 3650);
DISPLAY INVISIBLE (-8100 3650);
FORCEPROP 1 LAST PATH I194
J 2
(-7773 3775);
DISPLAY 0.872340 (-7773 3775);
PAINT GREEN (-7773 3775);
DISPLAY INVISIBLE (-7773 3775);
FORCEADD TAP..1
R 2
(-7775 3825);
FORCEPROP 3 LASTPIN (-7725 3825) SIG_NAME M_F_CPU0_SB_CB<6>
J 0
(-7715 3835);
DISPLAY 0.659574 (-7715 3835);
PAINT MONO (-7715 3835);
DISPLAY INVISIBLE (-7715 3835);
FORCEPROP 1 LASTPIN (-7725 3825) BN 6
J 2
(-7713 3833);
DISPLAY 0.489362 (-7713 3833);
PAINT GREEN (-7713 3833);
FORCEPROP 2 LAST CDS_LIB mstr_standard
J 0
(-7775 3825);
DISPLAY 0.723404 (-7775 3825);
PAINT MONO (-7775 3825);
DISPLAY INVISIBLE (-7775 3825);
FORCEPROP 1 LAST BODY_TYPE PLUMBING
J 2
(-7775 3875);
DISPLAY 0.872340 (-7775 3875);
PAINT GREEN (-7775 3875);
DISPLAY INVISIBLE (-7775 3875);
FORCEPROP 1 LAST HDL_TAP TRUE
J 2
(-8100 3700);
DISPLAY 0.872340 (-8100 3700);
DISPLAY INVISIBLE (-8100 3700);
FORCEPROP 1 LAST PATH I195
J 2
(-7773 3825);
DISPLAY 0.872340 (-7773 3825);
PAINT GREEN (-7773 3825);
DISPLAY INVISIBLE (-7773 3825);
FORCEADD TAP..1
R 2
(-7775 3875);
FORCEPROP 3 LASTPIN (-7725 3875) SIG_NAME M_F_CPU0_SB_CB<7>
J 0
(-7715 3885);
DISPLAY 0.659574 (-7715 3885);
PAINT MONO (-7715 3885);
DISPLAY INVISIBLE (-7715 3885);
FORCEPROP 1 LASTPIN (-7725 3875) BN 7
J 2
(-7713 3883);
DISPLAY 0.489362 (-7713 3883);
PAINT GREEN (-7713 3883);
FORCEPROP 2 LAST CDS_LIB mstr_standard
J 0
(-7775 3875);
DISPLAY 0.723404 (-7775 3875);
PAINT MONO (-7775 3875);
DISPLAY INVISIBLE (-7775 3875);
FORCEPROP 1 LAST BODY_TYPE PLUMBING
J 2
(-7775 3925);
DISPLAY 0.872340 (-7775 3925);
PAINT GREEN (-7775 3925);
DISPLAY INVISIBLE (-7775 3925);
FORCEPROP 1 LAST HDL_TAP TRUE
J 2
(-8100 3750);
DISPLAY 0.872340 (-8100 3750);
DISPLAY INVISIBLE (-8100 3750);
FORCEPROP 1 LAST PATH I196
J 2
(-7773 3875);
DISPLAY 0.872340 (-7773 3875);
PAINT GREEN (-7773 3875);
DISPLAY INVISIBLE (-7773 3875);
FORCEADD TAP..1
R 2
(-7775 3975);
FORCEPROP 3 LASTPIN (-7725 3975) SIG_NAME M_F_CPU0_SA_CB<0>
J 0
(-7715 3985);
DISPLAY 0.659574 (-7715 3985);
PAINT MONO (-7715 3985);
DISPLAY INVISIBLE (-7715 3985);
FORCEPROP 1 LASTPIN (-7725 3975) BN 0
J 2
(-7713 3983);
DISPLAY 0.489362 (-7713 3983);
PAINT GREEN (-7713 3983);
FORCEPROP 2 LAST CDS_LIB mstr_standard
J 0
(-7775 3975);
DISPLAY 0.723404 (-7775 3975);
PAINT MONO (-7775 3975);
DISPLAY INVISIBLE (-7775 3975);
FORCEPROP 1 LAST BODY_TYPE PLUMBING
J 2
(-7775 4025);
DISPLAY 0.872340 (-7775 4025);
PAINT GREEN (-7775 4025);
DISPLAY INVISIBLE (-7775 4025);
FORCEPROP 1 LAST HDL_TAP TRUE
J 2
(-8100 3850);
DISPLAY 0.872340 (-8100 3850);
DISPLAY INVISIBLE (-8100 3850);
FORCEPROP 1 LAST PATH I197
J 2
(-7773 3975);
DISPLAY 0.872340 (-7773 3975);
PAINT GREEN (-7773 3975);
DISPLAY INVISIBLE (-7773 3975);
FORCEADD TAP..1
R 2
(-7775 4025);
FORCEPROP 3 LASTPIN (-7725 4025) SIG_NAME M_F_CPU0_SA_CB<1>
J 0
(-7715 4035);
DISPLAY 0.659574 (-7715 4035);
PAINT MONO (-7715 4035);
DISPLAY INVISIBLE (-7715 4035);
FORCEPROP 1 LASTPIN (-7725 4025) BN 1
J 2
(-7713 4033);
DISPLAY 0.489362 (-7713 4033);
PAINT GREEN (-7713 4033);
FORCEPROP 2 LAST CDS_LIB mstr_standard
J 0
(-7775 4025);
DISPLAY 0.723404 (-7775 4025);
PAINT MONO (-7775 4025);
DISPLAY INVISIBLE (-7775 4025);
FORCEPROP 1 LAST BODY_TYPE PLUMBING
J 2
(-7775 4075);
DISPLAY 0.872340 (-7775 4075);
PAINT GREEN (-7775 4075);
DISPLAY INVISIBLE (-7775 4075);
FORCEPROP 1 LAST HDL_TAP TRUE
J 2
(-8100 3900);
DISPLAY 0.872340 (-8100 3900);
DISPLAY INVISIBLE (-8100 3900);
FORCEPROP 1 LAST PATH I198
J 2
(-7773 4025);
DISPLAY 0.872340 (-7773 4025);
PAINT GREEN (-7773 4025);
DISPLAY INVISIBLE (-7773 4025);
FORCEADD TAP..1
R 2
(-7775 4075);
FORCEPROP 3 LASTPIN (-7725 4075) SIG_NAME M_F_CPU0_SA_CB<2>
J 0
(-7715 4085);
DISPLAY 0.659574 (-7715 4085);
PAINT MONO (-7715 4085);
DISPLAY INVISIBLE (-7715 4085);
FORCEPROP 1 LASTPIN (-7725 4075) BN 2
J 2
(-7713 4083);
DISPLAY 0.489362 (-7713 4083);
PAINT GREEN (-7713 4083);
FORCEPROP 2 LAST CDS_LIB mstr_standard
J 0
(-7775 4075);
DISPLAY 0.723404 (-7775 4075);
PAINT MONO (-7775 4075);
DISPLAY INVISIBLE (-7775 4075);
FORCEPROP 1 LAST BODY_TYPE PLUMBING
J 2
(-7775 4125);
DISPLAY 0.872340 (-7775 4125);
PAINT GREEN (-7775 4125);
DISPLAY INVISIBLE (-7775 4125);
FORCEPROP 1 LAST HDL_TAP TRUE
J 2
(-8100 3950);
DISPLAY 0.872340 (-8100 3950);
DISPLAY INVISIBLE (-8100 3950);
FORCEPROP 1 LAST PATH I199
J 2
(-7773 4075);
DISPLAY 0.872340 (-7773 4075);
PAINT GREEN (-7773 4075);
DISPLAY INVISIBLE (-7773 4075);
FORCEADD TAP..1
R 2
(-7775 4125);
FORCEPROP 3 LASTPIN (-7725 4125) SIG_NAME M_F_CPU0_SA_CB<3>
J 0
(-7715 4135);
DISPLAY 0.659574 (-7715 4135);
PAINT MONO (-7715 4135);
DISPLAY INVISIBLE (-7715 4135);
FORCEPROP 1 LASTPIN (-7725 4125) BN 3
J 2
(-7713 4133);
DISPLAY 0.489362 (-7713 4133);
PAINT GREEN (-7713 4133);
FORCEPROP 2 LAST CDS_LIB mstr_standard
J 0
(-7775 4125);
DISPLAY 0.723404 (-7775 4125);
PAINT MONO (-7775 4125);
DISPLAY INVISIBLE (-7775 4125);
FORCEPROP 1 LAST BODY_TYPE PLUMBING
J 2
(-7775 4175);
DISPLAY 0.872340 (-7775 4175);
PAINT GREEN (-7775 4175);
DISPLAY INVISIBLE (-7775 4175);
FORCEPROP 1 LAST HDL_TAP TRUE
J 2
(-8100 4000);
DISPLAY 0.872340 (-8100 4000);
DISPLAY INVISIBLE (-8100 4000);
FORCEPROP 1 LAST PATH I200
J 2
(-7773 4125);
DISPLAY 0.872340 (-7773 4125);
PAINT GREEN (-7773 4125);
DISPLAY INVISIBLE (-7773 4125);
FORCEADD TAP..1
R 2
(-7775 4225);
FORCEPROP 3 LASTPIN (-7725 4225) SIG_NAME M_F_CPU0_SA_CB<5>
J 0
(-7715 4235);
DISPLAY 0.659574 (-7715 4235);
PAINT MONO (-7715 4235);
DISPLAY INVISIBLE (-7715 4235);
FORCEPROP 1 LASTPIN (-7725 4225) BN 5
J 2
(-7713 4233);
DISPLAY 0.489362 (-7713 4233);
PAINT GREEN (-7713 4233);
FORCEPROP 2 LAST CDS_LIB mstr_standard
J 0
(-7775 4225);
DISPLAY 0.723404 (-7775 4225);
PAINT MONO (-7775 4225);
DISPLAY INVISIBLE (-7775 4225);
FORCEPROP 1 LAST BODY_TYPE PLUMBING
J 2
(-7775 4275);
DISPLAY 0.872340 (-7775 4275);
PAINT GREEN (-7775 4275);
DISPLAY INVISIBLE (-7775 4275);
FORCEPROP 1 LAST HDL_TAP TRUE
J 2
(-8100 4100);
DISPLAY 0.872340 (-8100 4100);
DISPLAY INVISIBLE (-8100 4100);
FORCEPROP 1 LAST PATH I201
J 2
(-7773 4225);
DISPLAY 0.872340 (-7773 4225);
PAINT GREEN (-7773 4225);
DISPLAY INVISIBLE (-7773 4225);
FORCEADD TAP..1
R 2
(-7775 4175);
FORCEPROP 3 LASTPIN (-7725 4175) SIG_NAME M_F_CPU0_SA_CB<4>
J 0
(-7715 4185);
DISPLAY 0.659574 (-7715 4185);
PAINT MONO (-7715 4185);
DISPLAY INVISIBLE (-7715 4185);
FORCEPROP 1 LASTPIN (-7725 4175) BN 4
J 2
(-7713 4183);
DISPLAY 0.489362 (-7713 4183);
PAINT GREEN (-7713 4183);
FORCEPROP 2 LAST CDS_LIB mstr_standard
J 0
(-7775 4175);
DISPLAY 0.723404 (-7775 4175);
PAINT MONO (-7775 4175);
DISPLAY INVISIBLE (-7775 4175);
FORCEPROP 1 LAST BODY_TYPE PLUMBING
J 2
(-7775 4225);
DISPLAY 0.872340 (-7775 4225);
PAINT GREEN (-7775 4225);
DISPLAY INVISIBLE (-7775 4225);
FORCEPROP 1 LAST HDL_TAP TRUE
J 2
(-8100 4050);
DISPLAY 0.872340 (-8100 4050);
DISPLAY INVISIBLE (-8100 4050);
FORCEPROP 1 LAST PATH I202
J 2
(-7773 4175);
DISPLAY 0.872340 (-7773 4175);
PAINT GREEN (-7773 4175);
DISPLAY INVISIBLE (-7773 4175);
FORCEADD TAP..1
R 2
(-7775 4325);
FORCEPROP 3 LASTPIN (-7725 4325) SIG_NAME M_F_CPU0_SA_CB<7>
J 0
(-7715 4335);
DISPLAY 0.659574 (-7715 4335);
PAINT MONO (-7715 4335);
DISPLAY INVISIBLE (-7715 4335);
FORCEPROP 1 LASTPIN (-7725 4325) BN 7
J 2
(-7713 4333);
DISPLAY 0.489362 (-7713 4333);
PAINT GREEN (-7713 4333);
FORCEPROP 2 LAST CDS_LIB mstr_standard
J 0
(-7775 4325);
DISPLAY 0.723404 (-7775 4325);
PAINT MONO (-7775 4325);
DISPLAY INVISIBLE (-7775 4325);
FORCEPROP 1 LAST BODY_TYPE PLUMBING
J 2
(-7775 4375);
DISPLAY 0.872340 (-7775 4375);
PAINT GREEN (-7775 4375);
DISPLAY INVISIBLE (-7775 4375);
FORCEPROP 1 LAST HDL_TAP TRUE
J 2
(-8100 4200);
DISPLAY 0.872340 (-8100 4200);
DISPLAY INVISIBLE (-8100 4200);
FORCEPROP 1 LAST PATH I203
J 2
(-7773 4325);
DISPLAY 0.872340 (-7773 4325);
PAINT GREEN (-7773 4325);
DISPLAY INVISIBLE (-7773 4325);
FORCEADD TAP..1
R 2
(-7775 4275);
FORCEPROP 3 LASTPIN (-7725 4275) SIG_NAME M_F_CPU0_SA_CB<6>
J 0
(-7715 4285);
DISPLAY 0.659574 (-7715 4285);
PAINT MONO (-7715 4285);
DISPLAY INVISIBLE (-7715 4285);
FORCEPROP 1 LASTPIN (-7725 4275) BN 6
J 2
(-7713 4283);
DISPLAY 0.489362 (-7713 4283);
PAINT GREEN (-7713 4283);
FORCEPROP 2 LAST CDS_LIB mstr_standard
J 0
(-7775 4275);
DISPLAY 0.723404 (-7775 4275);
PAINT MONO (-7775 4275);
DISPLAY INVISIBLE (-7775 4275);
FORCEPROP 1 LAST BODY_TYPE PLUMBING
J 2
(-7775 4325);
DISPLAY 0.872340 (-7775 4325);
PAINT GREEN (-7775 4325);
DISPLAY INVISIBLE (-7775 4325);
FORCEPROP 1 LAST HDL_TAP TRUE
J 2
(-8100 4150);
DISPLAY 0.872340 (-8100 4150);
DISPLAY INVISIBLE (-8100 4150);
FORCEPROP 1 LAST PATH I204
J 2
(-7773 4275);
DISPLAY 0.872340 (-7773 4275);
PAINT GREEN (-7773 4275);
DISPLAY INVISIBLE (-7773 4275);
FORCEADD TAP..1
R 2
(-7775 5025);
FORCEPROP 3 LASTPIN (-7725 5025) SIG_NAME M_F_CPU0_SB_CA<0>
J 0
(-7715 5035);
DISPLAY 0.659574 (-7715 5035);
PAINT MONO (-7715 5035);
DISPLAY INVISIBLE (-7715 5035);
FORCEPROP 1 LASTPIN (-7725 5025) BN 0
J 2
(-7713 5033);
DISPLAY 0.489362 (-7713 5033);
PAINT GREEN (-7713 5033);
FORCEPROP 2 LAST CDS_LIB mstr_standard
J 0
(-7775 5025);
DISPLAY 0.723404 (-7775 5025);
PAINT MONO (-7775 5025);
DISPLAY INVISIBLE (-7775 5025);
FORCEPROP 1 LAST BODY_TYPE PLUMBING
J 2
(-7775 5075);
DISPLAY 0.872340 (-7775 5075);
PAINT GREEN (-7775 5075);
DISPLAY INVISIBLE (-7775 5075);
FORCEPROP 1 LAST HDL_TAP TRUE
J 2
(-8100 4900);
DISPLAY 0.872340 (-8100 4900);
DISPLAY INVISIBLE (-8100 4900);
FORCEPROP 1 LAST PATH I205
J 2
(-7773 5025);
DISPLAY 0.872340 (-7773 5025);
PAINT GREEN (-7773 5025);
DISPLAY INVISIBLE (-7773 5025);
FORCEADD TAP..1
R 2
(-7775 5125);
FORCEPROP 3 LASTPIN (-7725 5125) SIG_NAME M_F_CPU0_SB_CA<2>
J 0
(-7715 5135);
DISPLAY 0.659574 (-7715 5135);
PAINT MONO (-7715 5135);
DISPLAY INVISIBLE (-7715 5135);
FORCEPROP 1 LASTPIN (-7725 5125) BN 2
J 2
(-7713 5133);
DISPLAY 0.489362 (-7713 5133);
PAINT GREEN (-7713 5133);
FORCEPROP 2 LAST CDS_LIB mstr_standard
J 0
(-7775 5125);
DISPLAY 0.723404 (-7775 5125);
PAINT MONO (-7775 5125);
DISPLAY INVISIBLE (-7775 5125);
FORCEPROP 1 LAST BODY_TYPE PLUMBING
J 2
(-7775 5175);
DISPLAY 0.872340 (-7775 5175);
PAINT GREEN (-7775 5175);
DISPLAY INVISIBLE (-7775 5175);
FORCEPROP 1 LAST HDL_TAP TRUE
J 2
(-8100 5000);
DISPLAY 0.872340 (-8100 5000);
DISPLAY INVISIBLE (-8100 5000);
FORCEPROP 1 LAST PATH I206
J 2
(-7773 5125);
DISPLAY 0.872340 (-7773 5125);
PAINT GREEN (-7773 5125);
DISPLAY INVISIBLE (-7773 5125);
FORCEADD TAP..1
R 2
(-7775 5075);
FORCEPROP 3 LASTPIN (-7725 5075) SIG_NAME M_F_CPU0_SB_CA<1>
J 0
(-7715 5085);
DISPLAY 0.659574 (-7715 5085);
PAINT MONO (-7715 5085);
DISPLAY INVISIBLE (-7715 5085);
FORCEPROP 1 LASTPIN (-7725 5075) BN 1
J 2
(-7713 5083);
DISPLAY 0.489362 (-7713 5083);
PAINT GREEN (-7713 5083);
FORCEPROP 2 LAST CDS_LIB mstr_standard
J 0
(-7775 5075);
DISPLAY 0.723404 (-7775 5075);
PAINT MONO (-7775 5075);
DISPLAY INVISIBLE (-7775 5075);
FORCEPROP 1 LAST BODY_TYPE PLUMBING
J 2
(-7775 5125);
DISPLAY 0.872340 (-7775 5125);
PAINT GREEN (-7775 5125);
DISPLAY INVISIBLE (-7775 5125);
FORCEPROP 1 LAST HDL_TAP TRUE
J 2
(-8100 4950);
DISPLAY 0.872340 (-8100 4950);
DISPLAY INVISIBLE (-8100 4950);
FORCEPROP 1 LAST PATH I207
J 2
(-7773 5075);
DISPLAY 0.872340 (-7773 5075);
PAINT GREEN (-7773 5075);
DISPLAY INVISIBLE (-7773 5075);
FORCEADD TAP..1
R 2
(-7775 5225);
FORCEPROP 3 LASTPIN (-7725 5225) SIG_NAME M_F_CPU0_SB_CA<4>
J 0
(-7715 5235);
DISPLAY 0.659574 (-7715 5235);
PAINT MONO (-7715 5235);
DISPLAY INVISIBLE (-7715 5235);
FORCEPROP 1 LASTPIN (-7725 5225) BN 4
J 2
(-7713 5233);
DISPLAY 0.489362 (-7713 5233);
PAINT GREEN (-7713 5233);
FORCEPROP 2 LAST CDS_LIB mstr_standard
J 0
(-7775 5225);
DISPLAY 0.723404 (-7775 5225);
PAINT MONO (-7775 5225);
DISPLAY INVISIBLE (-7775 5225);
FORCEPROP 1 LAST BODY_TYPE PLUMBING
J 2
(-7775 5275);
DISPLAY 0.872340 (-7775 5275);
PAINT GREEN (-7775 5275);
DISPLAY INVISIBLE (-7775 5275);
FORCEPROP 1 LAST HDL_TAP TRUE
J 2
(-8100 5100);
DISPLAY 0.872340 (-8100 5100);
DISPLAY INVISIBLE (-8100 5100);
FORCEPROP 1 LAST PATH I208
J 2
(-7773 5225);
DISPLAY 0.872340 (-7773 5225);
PAINT GREEN (-7773 5225);
DISPLAY INVISIBLE (-7773 5225);
FORCEADD TAP..1
R 2
(-7775 5175);
FORCEPROP 3 LASTPIN (-7725 5175) SIG_NAME M_F_CPU0_SB_CA<3>
J 0
(-7715 5185);
DISPLAY 0.659574 (-7715 5185);
PAINT MONO (-7715 5185);
DISPLAY INVISIBLE (-7715 5185);
FORCEPROP 1 LASTPIN (-7725 5175) BN 3
J 2
(-7713 5183);
DISPLAY 0.489362 (-7713 5183);
PAINT GREEN (-7713 5183);
FORCEPROP 2 LAST CDS_LIB mstr_standard
J 0
(-7775 5175);
DISPLAY 0.723404 (-7775 5175);
PAINT MONO (-7775 5175);
DISPLAY INVISIBLE (-7775 5175);
FORCEPROP 1 LAST BODY_TYPE PLUMBING
J 2
(-7775 5225);
DISPLAY 0.872340 (-7775 5225);
PAINT GREEN (-7775 5225);
DISPLAY INVISIBLE (-7775 5225);
FORCEPROP 1 LAST HDL_TAP TRUE
J 2
(-8100 5050);
DISPLAY 0.872340 (-8100 5050);
DISPLAY INVISIBLE (-8100 5050);
FORCEPROP 1 LAST PATH I209
J 2
(-7773 5175);
DISPLAY 0.872340 (-7773 5175);
PAINT GREEN (-7773 5175);
DISPLAY INVISIBLE (-7773 5175);
FORCEADD TAP..1
R 2
(-7775 5275);
FORCEPROP 3 LASTPIN (-7725 5275) SIG_NAME M_F_CPU0_SB_CA<5>
J 0
(-7715 5285);
DISPLAY 0.659574 (-7715 5285);
PAINT MONO (-7715 5285);
DISPLAY INVISIBLE (-7715 5285);
FORCEPROP 1 LASTPIN (-7725 5275) BN 5
J 2
(-7713 5283);
DISPLAY 0.489362 (-7713 5283);
PAINT GREEN (-7713 5283);
FORCEPROP 2 LAST CDS_LIB mstr_standard
J 0
(-7775 5275);
DISPLAY 0.723404 (-7775 5275);
PAINT MONO (-7775 5275);
DISPLAY INVISIBLE (-7775 5275);
FORCEPROP 1 LAST BODY_TYPE PLUMBING
J 2
(-7775 5325);
DISPLAY 0.872340 (-7775 5325);
PAINT GREEN (-7775 5325);
DISPLAY INVISIBLE (-7775 5325);
FORCEPROP 1 LAST HDL_TAP TRUE
J 2
(-8100 5150);
DISPLAY 0.872340 (-8100 5150);
DISPLAY INVISIBLE (-8100 5150);
FORCEPROP 1 LAST PATH I210
J 2
(-7773 5275);
DISPLAY 0.872340 (-7773 5275);
PAINT GREEN (-7773 5275);
DISPLAY INVISIBLE (-7773 5275);
FORCEADD TAP..1
R 2
(-7775 5325);
FORCEPROP 3 LASTPIN (-7725 5325) SIG_NAME M_F_CPU0_SB_CA<6>
J 0
(-7715 5335);
DISPLAY 0.659574 (-7715 5335);
PAINT MONO (-7715 5335);
DISPLAY INVISIBLE (-7715 5335);
FORCEPROP 1 LASTPIN (-7725 5325) BN 6
J 2
(-7713 5333);
DISPLAY 0.489362 (-7713 5333);
PAINT GREEN (-7713 5333);
FORCEPROP 2 LAST CDS_LIB mstr_standard
J 0
(-7775 5325);
DISPLAY 0.723404 (-7775 5325);
PAINT MONO (-7775 5325);
DISPLAY INVISIBLE (-7775 5325);
FORCEPROP 1 LAST BODY_TYPE PLUMBING
J 2
(-7775 5375);
DISPLAY 0.872340 (-7775 5375);
PAINT GREEN (-7775 5375);
DISPLAY INVISIBLE (-7775 5375);
FORCEPROP 1 LAST HDL_TAP TRUE
J 2
(-8100 5200);
DISPLAY 0.872340 (-8100 5200);
DISPLAY INVISIBLE (-8100 5200);
FORCEPROP 1 LAST PATH I211
J 2
(-7773 5325);
DISPLAY 0.872340 (-7773 5325);
PAINT GREEN (-7773 5325);
DISPLAY INVISIBLE (-7773 5325);
FORCEADD TAP..1
R 2
(-7775 5425);
FORCEPROP 3 LASTPIN (-7725 5425) SIG_NAME M_F_CPU0_SA_CA<0>
J 0
(-7715 5435);
DISPLAY 0.659574 (-7715 5435);
PAINT MONO (-7715 5435);
DISPLAY INVISIBLE (-7715 5435);
FORCEPROP 1 LASTPIN (-7725 5425) BN 0
J 2
(-7713 5433);
DISPLAY 0.489362 (-7713 5433);
PAINT GREEN (-7713 5433);
FORCEPROP 2 LAST CDS_LIB mstr_standard
J 0
(-7775 5425);
DISPLAY 0.723404 (-7775 5425);
PAINT MONO (-7775 5425);
DISPLAY INVISIBLE (-7775 5425);
FORCEPROP 1 LAST BODY_TYPE PLUMBING
J 2
(-7775 5475);
DISPLAY 0.872340 (-7775 5475);
PAINT GREEN (-7775 5475);
DISPLAY INVISIBLE (-7775 5475);
FORCEPROP 1 LAST HDL_TAP TRUE
J 2
(-8100 5300);
DISPLAY 0.872340 (-8100 5300);
DISPLAY INVISIBLE (-8100 5300);
FORCEPROP 1 LAST PATH I212
J 2
(-7773 5425);
DISPLAY 0.872340 (-7773 5425);
PAINT GREEN (-7773 5425);
DISPLAY INVISIBLE (-7773 5425);
FORCEADD TAP..1
R 2
(-7775 5475);
FORCEPROP 3 LASTPIN (-7725 5475) SIG_NAME M_F_CPU0_SA_CA<1>
J 0
(-7715 5485);
DISPLAY 0.659574 (-7715 5485);
PAINT MONO (-7715 5485);
DISPLAY INVISIBLE (-7715 5485);
FORCEPROP 1 LASTPIN (-7725 5475) BN 1
J 2
(-7713 5483);
DISPLAY 0.489362 (-7713 5483);
PAINT GREEN (-7713 5483);
FORCEPROP 2 LAST CDS_LIB mstr_standard
J 0
(-7775 5475);
DISPLAY 0.723404 (-7775 5475);
PAINT MONO (-7775 5475);
DISPLAY INVISIBLE (-7775 5475);
FORCEPROP 1 LAST BODY_TYPE PLUMBING
J 2
(-7775 5525);
DISPLAY 0.872340 (-7775 5525);
PAINT GREEN (-7775 5525);
DISPLAY INVISIBLE (-7775 5525);
FORCEPROP 1 LAST HDL_TAP TRUE
J 2
(-8100 5350);
DISPLAY 0.872340 (-8100 5350);
DISPLAY INVISIBLE (-8100 5350);
FORCEPROP 1 LAST PATH I213
J 2
(-7773 5475);
DISPLAY 0.872340 (-7773 5475);
PAINT GREEN (-7773 5475);
DISPLAY INVISIBLE (-7773 5475);
FORCEADD TAP..1
R 2
(-7775 5525);
FORCEPROP 3 LASTPIN (-7725 5525) SIG_NAME M_F_CPU0_SA_CA<2>
J 0
(-7715 5535);
DISPLAY 0.659574 (-7715 5535);
PAINT MONO (-7715 5535);
DISPLAY INVISIBLE (-7715 5535);
FORCEPROP 1 LASTPIN (-7725 5525) BN 2
J 2
(-7713 5533);
DISPLAY 0.489362 (-7713 5533);
PAINT GREEN (-7713 5533);
FORCEPROP 2 LAST CDS_LIB mstr_standard
J 0
(-7775 5525);
DISPLAY 0.723404 (-7775 5525);
PAINT MONO (-7775 5525);
DISPLAY INVISIBLE (-7775 5525);
FORCEPROP 1 LAST BODY_TYPE PLUMBING
J 2
(-7775 5575);
DISPLAY 0.872340 (-7775 5575);
PAINT GREEN (-7775 5575);
DISPLAY INVISIBLE (-7775 5575);
FORCEPROP 1 LAST HDL_TAP TRUE
J 2
(-8100 5400);
DISPLAY 0.872340 (-8100 5400);
DISPLAY INVISIBLE (-8100 5400);
FORCEPROP 1 LAST PATH I214
J 2
(-7773 5525);
DISPLAY 0.872340 (-7773 5525);
PAINT GREEN (-7773 5525);
DISPLAY INVISIBLE (-7773 5525);
FORCEADD TAP..1
R 2
(-7775 5625);
FORCEPROP 3 LASTPIN (-7725 5625) SIG_NAME M_F_CPU0_SA_CA<4>
J 0
(-7715 5635);
DISPLAY 0.659574 (-7715 5635);
PAINT MONO (-7715 5635);
DISPLAY INVISIBLE (-7715 5635);
FORCEPROP 1 LASTPIN (-7725 5625) BN 4
J 2
(-7713 5633);
DISPLAY 0.489362 (-7713 5633);
PAINT GREEN (-7713 5633);
FORCEPROP 2 LAST CDS_LIB mstr_standard
J 0
(-7775 5625);
DISPLAY 0.723404 (-7775 5625);
PAINT MONO (-7775 5625);
DISPLAY INVISIBLE (-7775 5625);
FORCEPROP 1 LAST BODY_TYPE PLUMBING
J 2
(-7775 5675);
DISPLAY 0.872340 (-7775 5675);
PAINT GREEN (-7775 5675);
DISPLAY INVISIBLE (-7775 5675);
FORCEPROP 1 LAST HDL_TAP TRUE
J 2
(-8100 5500);
DISPLAY 0.872340 (-8100 5500);
DISPLAY INVISIBLE (-8100 5500);
FORCEPROP 1 LAST PATH I215
J 2
(-7773 5625);
DISPLAY 0.872340 (-7773 5625);
PAINT GREEN (-7773 5625);
DISPLAY INVISIBLE (-7773 5625);
FORCEADD TAP..1
R 2
(-7775 5575);
FORCEPROP 3 LASTPIN (-7725 5575) SIG_NAME M_F_CPU0_SA_CA<3>
J 0
(-7715 5585);
DISPLAY 0.659574 (-7715 5585);
PAINT MONO (-7715 5585);
DISPLAY INVISIBLE (-7715 5585);
FORCEPROP 1 LASTPIN (-7725 5575) BN 3
J 2
(-7713 5583);
DISPLAY 0.489362 (-7713 5583);
PAINT GREEN (-7713 5583);
FORCEPROP 2 LAST CDS_LIB mstr_standard
J 0
(-7775 5575);
DISPLAY 0.723404 (-7775 5575);
PAINT MONO (-7775 5575);
DISPLAY INVISIBLE (-7775 5575);
FORCEPROP 1 LAST BODY_TYPE PLUMBING
J 2
(-7775 5625);
DISPLAY 0.872340 (-7775 5625);
PAINT GREEN (-7775 5625);
DISPLAY INVISIBLE (-7775 5625);
FORCEPROP 1 LAST HDL_TAP TRUE
J 2
(-8100 5450);
DISPLAY 0.872340 (-8100 5450);
DISPLAY INVISIBLE (-8100 5450);
FORCEPROP 1 LAST PATH I216
J 2
(-7773 5575);
DISPLAY 0.872340 (-7773 5575);
PAINT GREEN (-7773 5575);
DISPLAY INVISIBLE (-7773 5575);
FORCEADD TAP..1
R 2
(-7775 5675);
FORCEPROP 3 LASTPIN (-7725 5675) SIG_NAME M_F_CPU0_SA_CA<5>
J 0
(-7715 5685);
DISPLAY 0.659574 (-7715 5685);
PAINT MONO (-7715 5685);
DISPLAY INVISIBLE (-7715 5685);
FORCEPROP 1 LASTPIN (-7725 5675) BN 5
J 2
(-7713 5683);
DISPLAY 0.489362 (-7713 5683);
PAINT GREEN (-7713 5683);
FORCEPROP 2 LAST CDS_LIB mstr_standard
J 0
(-7775 5675);
DISPLAY 0.723404 (-7775 5675);
PAINT MONO (-7775 5675);
DISPLAY INVISIBLE (-7775 5675);
FORCEPROP 1 LAST BODY_TYPE PLUMBING
J 2
(-7775 5725);
DISPLAY 0.872340 (-7775 5725);
PAINT GREEN (-7775 5725);
DISPLAY INVISIBLE (-7775 5725);
FORCEPROP 1 LAST HDL_TAP TRUE
J 2
(-8100 5550);
DISPLAY 0.872340 (-8100 5550);
DISPLAY INVISIBLE (-8100 5550);
FORCEPROP 1 LAST PATH I217
J 2
(-7773 5675);
DISPLAY 0.872340 (-7773 5675);
PAINT GREEN (-7773 5675);
DISPLAY INVISIBLE (-7773 5675);
FORCEADD TAP..1
R 2
(-7775 5725);
FORCEPROP 3 LASTPIN (-7725 5725) SIG_NAME M_F_CPU0_SA_CA<6>
J 0
(-7715 5735);
DISPLAY 0.659574 (-7715 5735);
PAINT MONO (-7715 5735);
DISPLAY INVISIBLE (-7715 5735);
FORCEPROP 1 LASTPIN (-7725 5725) BN 6
J 2
(-7713 5733);
DISPLAY 0.489362 (-7713 5733);
PAINT GREEN (-7713 5733);
FORCEPROP 2 LAST CDS_LIB mstr_standard
J 0
(-7775 5725);
DISPLAY 0.723404 (-7775 5725);
PAINT MONO (-7775 5725);
DISPLAY INVISIBLE (-7775 5725);
FORCEPROP 1 LAST BODY_TYPE PLUMBING
J 2
(-7775 5775);
DISPLAY 0.872340 (-7775 5775);
PAINT GREEN (-7775 5775);
DISPLAY INVISIBLE (-7775 5775);
FORCEPROP 1 LAST HDL_TAP TRUE
J 2
(-8100 5600);
DISPLAY 0.872340 (-8100 5600);
DISPLAY INVISIBLE (-8100 5600);
FORCEPROP 1 LAST PATH I218
J 2
(-7773 5725);
DISPLAY 0.872340 (-7773 5725);
PAINT GREEN (-7773 5725);
DISPLAY INVISIBLE (-7773 5725);
FORCEADD TAP..1
(-6075 5625);
FORCEPROP 3 LASTPIN (-6125 5625) SIG_NAME M_F_CPU0_SA_DQ<29>
J 0
(-6115 5635);
DISPLAY 0.659574 (-6115 5635);
PAINT MONO (-6115 5635);
DISPLAY INVISIBLE (-6115 5635);
FORCEPROP 1 LASTPIN (-6125 5625) BN 29
J 0
(-6137 5633);
DISPLAY 0.489362 (-6137 5633);
PAINT GREEN (-6137 5633);
FORCEPROP 2 LAST CDS_LIB mstr_standard
J 0
(-6075 5625);
DISPLAY 0.723404 (-6075 5625);
PAINT MONO (-6075 5625);
DISPLAY INVISIBLE (-6075 5625);
FORCEPROP 1 LAST BODY_TYPE PLUMBING
J 0
(-6075 5675);
DISPLAY 0.872340 (-6075 5675);
PAINT GREEN (-6075 5675);
DISPLAY INVISIBLE (-6075 5675);
FORCEPROP 1 LAST HDL_TAP TRUE
J 0
(-5750 5500);
DISPLAY 0.872340 (-5750 5500);
DISPLAY INVISIBLE (-5750 5500);
FORCEPROP 1 LAST PATH I219
J 0
(-6077 5625);
DISPLAY 0.872340 (-6077 5625);
PAINT GREEN (-6077 5625);
DISPLAY INVISIBLE (-6077 5625);
FORCEADD TAP..1
(-6075 5675);
FORCEPROP 3 LASTPIN (-6125 5675) SIG_NAME M_F_CPU0_SA_DQ<30>
J 0
(-6115 5685);
DISPLAY 0.659574 (-6115 5685);
PAINT MONO (-6115 5685);
DISPLAY INVISIBLE (-6115 5685);
FORCEPROP 1 LASTPIN (-6125 5675) BN 30
J 0
(-6137 5683);
DISPLAY 0.489362 (-6137 5683);
PAINT GREEN (-6137 5683);
FORCEPROP 2 LAST CDS_LIB mstr_standard
J 0
(-6075 5675);
DISPLAY 0.723404 (-6075 5675);
PAINT MONO (-6075 5675);
DISPLAY INVISIBLE (-6075 5675);
FORCEPROP 1 LAST BODY_TYPE PLUMBING
J 0
(-6075 5725);
DISPLAY 0.872340 (-6075 5725);
PAINT GREEN (-6075 5725);
DISPLAY INVISIBLE (-6075 5725);
FORCEPROP 1 LAST HDL_TAP TRUE
J 0
(-5750 5550);
DISPLAY 0.872340 (-5750 5550);
DISPLAY INVISIBLE (-5750 5550);
FORCEPROP 1 LAST PATH I220
J 0
(-6077 5675);
DISPLAY 0.872340 (-6077 5675);
PAINT GREEN (-6077 5675);
DISPLAY INVISIBLE (-6077 5675);
FORCEADD TAP..1
(-6075 5575);
FORCEPROP 3 LASTPIN (-6125 5575) SIG_NAME M_F_CPU0_SA_DQ<28>
J 0
(-6115 5585);
DISPLAY 0.659574 (-6115 5585);
PAINT MONO (-6115 5585);
DISPLAY INVISIBLE (-6115 5585);
FORCEPROP 1 LASTPIN (-6125 5575) BN 28
J 0
(-6137 5583);
DISPLAY 0.489362 (-6137 5583);
PAINT GREEN (-6137 5583);
FORCEPROP 2 LAST CDS_LIB mstr_standard
J 0
(-6075 5575);
DISPLAY 0.723404 (-6075 5575);
PAINT MONO (-6075 5575);
DISPLAY INVISIBLE (-6075 5575);
FORCEPROP 1 LAST BODY_TYPE PLUMBING
J 0
(-6075 5625);
DISPLAY 0.872340 (-6075 5625);
PAINT GREEN (-6075 5625);
DISPLAY INVISIBLE (-6075 5625);
FORCEPROP 1 LAST HDL_TAP TRUE
J 0
(-5750 5450);
DISPLAY 0.872340 (-5750 5450);
DISPLAY INVISIBLE (-5750 5450);
FORCEPROP 1 LAST PATH I221
J 0
(-6077 5575);
DISPLAY 0.872340 (-6077 5575);
PAINT GREEN (-6077 5575);
DISPLAY INVISIBLE (-6077 5575);
FORCEADD TAP..1
(-6075 5525);
FORCEPROP 3 LASTPIN (-6125 5525) SIG_NAME M_F_CPU0_SA_DQ<27>
J 0
(-6115 5535);
DISPLAY 0.659574 (-6115 5535);
PAINT MONO (-6115 5535);
DISPLAY INVISIBLE (-6115 5535);
FORCEPROP 1 LASTPIN (-6125 5525) BN 27
J 0
(-6137 5533);
DISPLAY 0.489362 (-6137 5533);
PAINT GREEN (-6137 5533);
FORCEPROP 2 LAST CDS_LIB mstr_standard
J 0
(-6075 5525);
DISPLAY 0.723404 (-6075 5525);
PAINT MONO (-6075 5525);
DISPLAY INVISIBLE (-6075 5525);
FORCEPROP 1 LAST BODY_TYPE PLUMBING
J 0
(-6075 5575);
DISPLAY 0.872340 (-6075 5575);
PAINT GREEN (-6075 5575);
DISPLAY INVISIBLE (-6075 5575);
FORCEPROP 1 LAST HDL_TAP TRUE
J 0
(-5750 5400);
DISPLAY 0.872340 (-5750 5400);
DISPLAY INVISIBLE (-5750 5400);
FORCEPROP 1 LAST PATH I222
J 0
(-6077 5525);
DISPLAY 0.872340 (-6077 5525);
PAINT GREEN (-6077 5525);
DISPLAY INVISIBLE (-6077 5525);
FORCEADD TAP..1
(-6075 5725);
FORCEPROP 3 LASTPIN (-6125 5725) SIG_NAME M_F_CPU0_SA_DQ<31>
J 0
(-6115 5735);
DISPLAY 0.659574 (-6115 5735);
PAINT MONO (-6115 5735);
DISPLAY INVISIBLE (-6115 5735);
FORCEPROP 1 LASTPIN (-6125 5725) BN 31
J 0
(-6137 5733);
DISPLAY 0.489362 (-6137 5733);
PAINT GREEN (-6137 5733);
FORCEPROP 2 LAST CDS_LIB mstr_standard
J 0
(-6075 5725);
DISPLAY 0.723404 (-6075 5725);
PAINT MONO (-6075 5725);
DISPLAY INVISIBLE (-6075 5725);
FORCEPROP 1 LAST BODY_TYPE PLUMBING
J 0
(-6075 5775);
DISPLAY 0.872340 (-6075 5775);
PAINT GREEN (-6075 5775);
DISPLAY INVISIBLE (-6075 5775);
FORCEPROP 1 LAST HDL_TAP TRUE
J 0
(-5750 5600);
DISPLAY 0.872340 (-5750 5600);
DISPLAY INVISIBLE (-5750 5600);
FORCEPROP 1 LAST PATH I223
J 0
(-6077 5725);
DISPLAY 0.872340 (-6077 5725);
PAINT GREEN (-6077 5725);
DISPLAY INVISIBLE (-6077 5725);
FORCEADD TAP..1
(-6075 5475);
FORCEPROP 3 LASTPIN (-6125 5475) SIG_NAME M_F_CPU0_SA_DQ<26>
J 0
(-6115 5485);
DISPLAY 0.659574 (-6115 5485);
PAINT MONO (-6115 5485);
DISPLAY INVISIBLE (-6115 5485);
FORCEPROP 1 LASTPIN (-6125 5475) BN 26
J 0
(-6137 5483);
DISPLAY 0.489362 (-6137 5483);
PAINT GREEN (-6137 5483);
FORCEPROP 2 LAST CDS_LIB mstr_standard
J 0
(-6075 5475);
DISPLAY 0.723404 (-6075 5475);
PAINT MONO (-6075 5475);
DISPLAY INVISIBLE (-6075 5475);
FORCEPROP 1 LAST BODY_TYPE PLUMBING
J 0
(-6075 5525);
DISPLAY 0.872340 (-6075 5525);
PAINT GREEN (-6075 5525);
DISPLAY INVISIBLE (-6075 5525);
FORCEPROP 1 LAST HDL_TAP TRUE
J 0
(-5750 5350);
DISPLAY 0.872340 (-5750 5350);
DISPLAY INVISIBLE (-5750 5350);
FORCEPROP 1 LAST PATH I224
J 0
(-6077 5475);
DISPLAY 0.872340 (-6077 5475);
PAINT GREEN (-6077 5475);
DISPLAY INVISIBLE (-6077 5475);
FORCEADD TAP..1
(-6075 5425);
FORCEPROP 3 LASTPIN (-6125 5425) SIG_NAME M_F_CPU0_SA_DQ<25>
J 0
(-6115 5435);
DISPLAY 0.659574 (-6115 5435);
PAINT MONO (-6115 5435);
DISPLAY INVISIBLE (-6115 5435);
FORCEPROP 1 LASTPIN (-6125 5425) BN 25
J 0
(-6137 5433);
DISPLAY 0.489362 (-6137 5433);
PAINT GREEN (-6137 5433);
FORCEPROP 2 LAST CDS_LIB mstr_standard
J 0
(-6075 5425);
DISPLAY 0.723404 (-6075 5425);
PAINT MONO (-6075 5425);
DISPLAY INVISIBLE (-6075 5425);
FORCEPROP 1 LAST BODY_TYPE PLUMBING
J 0
(-6075 5475);
DISPLAY 0.872340 (-6075 5475);
PAINT GREEN (-6075 5475);
DISPLAY INVISIBLE (-6075 5475);
FORCEPROP 1 LAST HDL_TAP TRUE
J 0
(-5750 5300);
DISPLAY 0.872340 (-5750 5300);
DISPLAY INVISIBLE (-5750 5300);
FORCEPROP 1 LAST PATH I225
J 0
(-6077 5425);
DISPLAY 0.872340 (-6077 5425);
PAINT GREEN (-6077 5425);
DISPLAY INVISIBLE (-6077 5425);
FORCEADD TAP..1
(-6075 5375);
FORCEPROP 3 LASTPIN (-6125 5375) SIG_NAME M_F_CPU0_SA_DQ<24>
J 0
(-6115 5385);
DISPLAY 0.659574 (-6115 5385);
PAINT MONO (-6115 5385);
DISPLAY INVISIBLE (-6115 5385);
FORCEPROP 1 LASTPIN (-6125 5375) BN 24
J 0
(-6137 5383);
DISPLAY 0.489362 (-6137 5383);
PAINT GREEN (-6137 5383);
FORCEPROP 2 LAST CDS_LIB mstr_standard
J 0
(-6075 5375);
DISPLAY 0.723404 (-6075 5375);
PAINT MONO (-6075 5375);
DISPLAY INVISIBLE (-6075 5375);
FORCEPROP 1 LAST BODY_TYPE PLUMBING
J 0
(-6075 5425);
DISPLAY 0.872340 (-6075 5425);
PAINT GREEN (-6075 5425);
DISPLAY INVISIBLE (-6075 5425);
FORCEPROP 1 LAST HDL_TAP TRUE
J 0
(-5750 5250);
DISPLAY 0.872340 (-5750 5250);
DISPLAY INVISIBLE (-5750 5250);
FORCEPROP 1 LAST PATH I226
J 0
(-6077 5375);
DISPLAY 0.872340 (-6077 5375);
PAINT GREEN (-6077 5375);
DISPLAY INVISIBLE (-6077 5375);
FORCEADD TAP..1
(-6075 5275);
FORCEPROP 3 LASTPIN (-6125 5275) SIG_NAME M_F_CPU0_SA_DQ<22>
J 0
(-6115 5285);
DISPLAY 0.659574 (-6115 5285);
PAINT MONO (-6115 5285);
DISPLAY INVISIBLE (-6115 5285);
FORCEPROP 1 LASTPIN (-6125 5275) BN 22
J 0
(-6137 5283);
DISPLAY 0.489362 (-6137 5283);
PAINT GREEN (-6137 5283);
FORCEPROP 2 LAST CDS_LIB mstr_standard
J 0
(-6075 5275);
DISPLAY 0.723404 (-6075 5275);
PAINT MONO (-6075 5275);
DISPLAY INVISIBLE (-6075 5275);
FORCEPROP 1 LAST BODY_TYPE PLUMBING
J 0
(-6075 5325);
DISPLAY 0.872340 (-6075 5325);
PAINT GREEN (-6075 5325);
DISPLAY INVISIBLE (-6075 5325);
FORCEPROP 1 LAST HDL_TAP TRUE
J 0
(-5750 5150);
DISPLAY 0.872340 (-5750 5150);
DISPLAY INVISIBLE (-5750 5150);
FORCEPROP 1 LAST PATH I227
J 0
(-6077 5275);
DISPLAY 0.872340 (-6077 5275);
PAINT GREEN (-6077 5275);
DISPLAY INVISIBLE (-6077 5275);
FORCEADD TAP..1
(-6075 5225);
FORCEPROP 3 LASTPIN (-6125 5225) SIG_NAME M_F_CPU0_SA_DQ<21>
J 0
(-6115 5235);
DISPLAY 0.659574 (-6115 5235);
PAINT MONO (-6115 5235);
DISPLAY INVISIBLE (-6115 5235);
FORCEPROP 1 LASTPIN (-6125 5225) BN 21
J 0
(-6137 5233);
DISPLAY 0.489362 (-6137 5233);
PAINT GREEN (-6137 5233);
FORCEPROP 2 LAST CDS_LIB mstr_standard
J 0
(-6075 5225);
DISPLAY 0.723404 (-6075 5225);
PAINT MONO (-6075 5225);
DISPLAY INVISIBLE (-6075 5225);
FORCEPROP 1 LAST BODY_TYPE PLUMBING
J 0
(-6075 5275);
DISPLAY 0.872340 (-6075 5275);
PAINT GREEN (-6075 5275);
DISPLAY INVISIBLE (-6075 5275);
FORCEPROP 1 LAST HDL_TAP TRUE
J 0
(-5750 5100);
DISPLAY 0.872340 (-5750 5100);
DISPLAY INVISIBLE (-5750 5100);
FORCEPROP 1 LAST PATH I228
J 0
(-6077 5225);
DISPLAY 0.872340 (-6077 5225);
PAINT GREEN (-6077 5225);
DISPLAY INVISIBLE (-6077 5225);
FORCEADD TAP..1
(-6075 5325);
FORCEPROP 3 LASTPIN (-6125 5325) SIG_NAME M_F_CPU0_SA_DQ<23>
J 0
(-6115 5335);
DISPLAY 0.659574 (-6115 5335);
PAINT MONO (-6115 5335);
DISPLAY INVISIBLE (-6115 5335);
FORCEPROP 1 LASTPIN (-6125 5325) BN 23
J 0
(-6137 5333);
DISPLAY 0.489362 (-6137 5333);
PAINT GREEN (-6137 5333);
FORCEPROP 2 LAST CDS_LIB mstr_standard
J 0
(-6075 5325);
DISPLAY 0.723404 (-6075 5325);
PAINT MONO (-6075 5325);
DISPLAY INVISIBLE (-6075 5325);
FORCEPROP 1 LAST BODY_TYPE PLUMBING
J 0
(-6075 5375);
DISPLAY 0.872340 (-6075 5375);
PAINT GREEN (-6075 5375);
DISPLAY INVISIBLE (-6075 5375);
FORCEPROP 1 LAST HDL_TAP TRUE
J 0
(-5750 5200);
DISPLAY 0.872340 (-5750 5200);
DISPLAY INVISIBLE (-5750 5200);
FORCEPROP 1 LAST PATH I229
J 0
(-6077 5325);
DISPLAY 0.872340 (-6077 5325);
PAINT GREEN (-6077 5325);
DISPLAY INVISIBLE (-6077 5325);
FORCEADD TAP..1
(-6075 5125);
FORCEPROP 3 LASTPIN (-6125 5125) SIG_NAME M_F_CPU0_SA_DQ<19>
J 0
(-6115 5135);
DISPLAY 0.659574 (-6115 5135);
PAINT MONO (-6115 5135);
DISPLAY INVISIBLE (-6115 5135);
FORCEPROP 1 LASTPIN (-6125 5125) BN 19
J 0
(-6137 5133);
DISPLAY 0.489362 (-6137 5133);
PAINT GREEN (-6137 5133);
FORCEPROP 2 LAST CDS_LIB mstr_standard
J 0
(-6075 5125);
DISPLAY 0.723404 (-6075 5125);
PAINT MONO (-6075 5125);
DISPLAY INVISIBLE (-6075 5125);
FORCEPROP 1 LAST BODY_TYPE PLUMBING
J 0
(-6075 5175);
DISPLAY 0.872340 (-6075 5175);
PAINT GREEN (-6075 5175);
DISPLAY INVISIBLE (-6075 5175);
FORCEPROP 1 LAST HDL_TAP TRUE
J 0
(-5750 5000);
DISPLAY 0.872340 (-5750 5000);
DISPLAY INVISIBLE (-5750 5000);
FORCEPROP 1 LAST PATH I230
J 0
(-6077 5125);
DISPLAY 0.872340 (-6077 5125);
PAINT GREEN (-6077 5125);
DISPLAY INVISIBLE (-6077 5125);
FORCEADD TAP..1
(-6075 5175);
FORCEPROP 3 LASTPIN (-6125 5175) SIG_NAME M_F_CPU0_SA_DQ<20>
J 0
(-6115 5185);
DISPLAY 0.659574 (-6115 5185);
PAINT MONO (-6115 5185);
DISPLAY INVISIBLE (-6115 5185);
FORCEPROP 1 LASTPIN (-6125 5175) BN 20
J 0
(-6137 5183);
DISPLAY 0.489362 (-6137 5183);
PAINT GREEN (-6137 5183);
FORCEPROP 2 LAST CDS_LIB mstr_standard
J 0
(-6075 5175);
DISPLAY 0.723404 (-6075 5175);
PAINT MONO (-6075 5175);
DISPLAY INVISIBLE (-6075 5175);
FORCEPROP 1 LAST BODY_TYPE PLUMBING
J 0
(-6075 5225);
DISPLAY 0.872340 (-6075 5225);
PAINT GREEN (-6075 5225);
DISPLAY INVISIBLE (-6075 5225);
FORCEPROP 1 LAST HDL_TAP TRUE
J 0
(-5750 5050);
DISPLAY 0.872340 (-5750 5050);
DISPLAY INVISIBLE (-5750 5050);
FORCEPROP 1 LAST PATH I231
J 0
(-6077 5175);
DISPLAY 0.872340 (-6077 5175);
PAINT GREEN (-6077 5175);
DISPLAY INVISIBLE (-6077 5175);
FORCEADD TAP..1
(-6075 4975);
FORCEPROP 3 LASTPIN (-6125 4975) SIG_NAME M_F_CPU0_SA_DQ<16>
J 0
(-6115 4985);
DISPLAY 0.659574 (-6115 4985);
PAINT MONO (-6115 4985);
DISPLAY INVISIBLE (-6115 4985);
FORCEPROP 1 LASTPIN (-6125 4975) BN 16
J 0
(-6137 4983);
DISPLAY 0.489362 (-6137 4983);
PAINT GREEN (-6137 4983);
FORCEPROP 2 LAST CDS_LIB mstr_standard
J 0
(-6075 4975);
DISPLAY 0.723404 (-6075 4975);
PAINT MONO (-6075 4975);
DISPLAY INVISIBLE (-6075 4975);
FORCEPROP 1 LAST BODY_TYPE PLUMBING
J 0
(-6075 5025);
DISPLAY 0.872340 (-6075 5025);
PAINT GREEN (-6075 5025);
DISPLAY INVISIBLE (-6075 5025);
FORCEPROP 1 LAST HDL_TAP TRUE
J 0
(-5750 4850);
DISPLAY 0.872340 (-5750 4850);
DISPLAY INVISIBLE (-5750 4850);
FORCEPROP 1 LAST PATH I232
J 0
(-6077 4975);
DISPLAY 0.872340 (-6077 4975);
PAINT GREEN (-6077 4975);
DISPLAY INVISIBLE (-6077 4975);
FORCEADD TAP..1
(-6075 5075);
FORCEPROP 3 LASTPIN (-6125 5075) SIG_NAME M_F_CPU0_SA_DQ<18>
J 0
(-6115 5085);
DISPLAY 0.659574 (-6115 5085);
PAINT MONO (-6115 5085);
DISPLAY INVISIBLE (-6115 5085);
FORCEPROP 1 LASTPIN (-6125 5075) BN 18
J 0
(-6137 5083);
DISPLAY 0.489362 (-6137 5083);
PAINT GREEN (-6137 5083);
FORCEPROP 2 LAST CDS_LIB mstr_standard
J 0
(-6075 5075);
DISPLAY 0.723404 (-6075 5075);
PAINT MONO (-6075 5075);
DISPLAY INVISIBLE (-6075 5075);
FORCEPROP 1 LAST BODY_TYPE PLUMBING
J 0
(-6075 5125);
DISPLAY 0.872340 (-6075 5125);
PAINT GREEN (-6075 5125);
DISPLAY INVISIBLE (-6075 5125);
FORCEPROP 1 LAST HDL_TAP TRUE
J 0
(-5750 4950);
DISPLAY 0.872340 (-5750 4950);
DISPLAY INVISIBLE (-5750 4950);
FORCEPROP 1 LAST PATH I233
J 0
(-6077 5075);
DISPLAY 0.872340 (-6077 5075);
PAINT GREEN (-6077 5075);
DISPLAY INVISIBLE (-6077 5075);
FORCEADD TAP..1
(-6075 5025);
FORCEPROP 3 LASTPIN (-6125 5025) SIG_NAME M_F_CPU0_SA_DQ<17>
J 0
(-6115 5035);
DISPLAY 0.659574 (-6115 5035);
PAINT MONO (-6115 5035);
DISPLAY INVISIBLE (-6115 5035);
FORCEPROP 1 LASTPIN (-6125 5025) BN 17
J 0
(-6137 5033);
DISPLAY 0.489362 (-6137 5033);
PAINT GREEN (-6137 5033);
FORCEPROP 2 LAST CDS_LIB mstr_standard
J 0
(-6075 5025);
DISPLAY 0.723404 (-6075 5025);
PAINT MONO (-6075 5025);
DISPLAY INVISIBLE (-6075 5025);
FORCEPROP 1 LAST BODY_TYPE PLUMBING
J 0
(-6075 5075);
DISPLAY 0.872340 (-6075 5075);
PAINT GREEN (-6075 5075);
DISPLAY INVISIBLE (-6075 5075);
FORCEPROP 1 LAST HDL_TAP TRUE
J 0
(-5750 4900);
DISPLAY 0.872340 (-5750 4900);
DISPLAY INVISIBLE (-5750 4900);
FORCEPROP 1 LAST PATH I234
J 0
(-6077 5025);
DISPLAY 0.872340 (-6077 5025);
PAINT GREEN (-6077 5025);
DISPLAY INVISIBLE (-6077 5025);
FORCEADD TAP..1
(-6075 4725);
FORCEPROP 3 LASTPIN (-6125 4725) SIG_NAME M_F_CPU0_SA_DQ<11>
J 0
(-6115 4735);
DISPLAY 0.659574 (-6115 4735);
PAINT MONO (-6115 4735);
DISPLAY INVISIBLE (-6115 4735);
FORCEPROP 1 LASTPIN (-6125 4725) BN 11
J 0
(-6137 4733);
DISPLAY 0.489362 (-6137 4733);
PAINT GREEN (-6137 4733);
FORCEPROP 2 LAST CDS_LIB mstr_standard
J 0
(-6075 4725);
DISPLAY 0.723404 (-6075 4725);
PAINT MONO (-6075 4725);
DISPLAY INVISIBLE (-6075 4725);
FORCEPROP 1 LAST BODY_TYPE PLUMBING
J 0
(-6075 4775);
DISPLAY 0.872340 (-6075 4775);
PAINT GREEN (-6075 4775);
DISPLAY INVISIBLE (-6075 4775);
FORCEPROP 1 LAST HDL_TAP TRUE
J 0
(-5750 4600);
DISPLAY 0.872340 (-5750 4600);
DISPLAY INVISIBLE (-5750 4600);
FORCEPROP 1 LAST PATH I235
J 0
(-6077 4725);
DISPLAY 0.872340 (-6077 4725);
PAINT GREEN (-6077 4725);
DISPLAY INVISIBLE (-6077 4725);
FORCEADD TAP..1
(-6075 4775);
FORCEPROP 3 LASTPIN (-6125 4775) SIG_NAME M_F_CPU0_SA_DQ<12>
J 0
(-6115 4785);
DISPLAY 0.659574 (-6115 4785);
PAINT MONO (-6115 4785);
DISPLAY INVISIBLE (-6115 4785);
FORCEPROP 1 LASTPIN (-6125 4775) BN 12
J 0
(-6137 4783);
DISPLAY 0.489362 (-6137 4783);
PAINT GREEN (-6137 4783);
FORCEPROP 2 LAST CDS_LIB mstr_standard
J 0
(-6075 4775);
DISPLAY 0.723404 (-6075 4775);
PAINT MONO (-6075 4775);
DISPLAY INVISIBLE (-6075 4775);
FORCEPROP 1 LAST BODY_TYPE PLUMBING
J 0
(-6075 4825);
DISPLAY 0.872340 (-6075 4825);
PAINT GREEN (-6075 4825);
DISPLAY INVISIBLE (-6075 4825);
FORCEPROP 1 LAST HDL_TAP TRUE
J 0
(-5750 4650);
DISPLAY 0.872340 (-5750 4650);
DISPLAY INVISIBLE (-5750 4650);
FORCEPROP 1 LAST PATH I236
J 0
(-6077 4775);
DISPLAY 0.872340 (-6077 4775);
PAINT GREEN (-6077 4775);
DISPLAY INVISIBLE (-6077 4775);
FORCEADD TAP..1
(-6075 4825);
FORCEPROP 3 LASTPIN (-6125 4825) SIG_NAME M_F_CPU0_SA_DQ<13>
J 0
(-6115 4835);
DISPLAY 0.659574 (-6115 4835);
PAINT MONO (-6115 4835);
DISPLAY INVISIBLE (-6115 4835);
FORCEPROP 1 LASTPIN (-6125 4825) BN 13
J 0
(-6137 4833);
DISPLAY 0.489362 (-6137 4833);
PAINT GREEN (-6137 4833);
FORCEPROP 2 LAST CDS_LIB mstr_standard
J 0
(-6075 4825);
DISPLAY 0.723404 (-6075 4825);
PAINT MONO (-6075 4825);
DISPLAY INVISIBLE (-6075 4825);
FORCEPROP 1 LAST BODY_TYPE PLUMBING
J 0
(-6075 4875);
DISPLAY 0.872340 (-6075 4875);
PAINT GREEN (-6075 4875);
DISPLAY INVISIBLE (-6075 4875);
FORCEPROP 1 LAST HDL_TAP TRUE
J 0
(-5750 4700);
DISPLAY 0.872340 (-5750 4700);
DISPLAY INVISIBLE (-5750 4700);
FORCEPROP 1 LAST PATH I237
J 0
(-6077 4825);
DISPLAY 0.872340 (-6077 4825);
PAINT GREEN (-6077 4825);
DISPLAY INVISIBLE (-6077 4825);
FORCEADD TAP..1
(-6075 4925);
FORCEPROP 3 LASTPIN (-6125 4925) SIG_NAME M_F_CPU0_SA_DQ<15>
J 0
(-6115 4935);
DISPLAY 0.659574 (-6115 4935);
PAINT MONO (-6115 4935);
DISPLAY INVISIBLE (-6115 4935);
FORCEPROP 1 LASTPIN (-6125 4925) BN 15
J 0
(-6137 4933);
DISPLAY 0.489362 (-6137 4933);
PAINT GREEN (-6137 4933);
FORCEPROP 2 LAST CDS_LIB mstr_standard
J 0
(-6075 4925);
DISPLAY 0.723404 (-6075 4925);
PAINT MONO (-6075 4925);
DISPLAY INVISIBLE (-6075 4925);
FORCEPROP 1 LAST BODY_TYPE PLUMBING
J 0
(-6075 4975);
DISPLAY 0.872340 (-6075 4975);
PAINT GREEN (-6075 4975);
DISPLAY INVISIBLE (-6075 4975);
FORCEPROP 1 LAST HDL_TAP TRUE
J 0
(-5750 4800);
DISPLAY 0.872340 (-5750 4800);
DISPLAY INVISIBLE (-5750 4800);
FORCEPROP 1 LAST PATH I238
J 0
(-6077 4925);
DISPLAY 0.872340 (-6077 4925);
PAINT GREEN (-6077 4925);
DISPLAY INVISIBLE (-6077 4925);
FORCEADD TAP..1
(-6075 4875);
FORCEPROP 3 LASTPIN (-6125 4875) SIG_NAME M_F_CPU0_SA_DQ<14>
J 0
(-6115 4885);
DISPLAY 0.659574 (-6115 4885);
PAINT MONO (-6115 4885);
DISPLAY INVISIBLE (-6115 4885);
FORCEPROP 1 LASTPIN (-6125 4875) BN 14
J 0
(-6137 4883);
DISPLAY 0.489362 (-6137 4883);
PAINT GREEN (-6137 4883);
FORCEPROP 2 LAST CDS_LIB mstr_standard
J 0
(-6075 4875);
DISPLAY 0.723404 (-6075 4875);
PAINT MONO (-6075 4875);
DISPLAY INVISIBLE (-6075 4875);
FORCEPROP 1 LAST BODY_TYPE PLUMBING
J 0
(-6075 4925);
DISPLAY 0.872340 (-6075 4925);
PAINT GREEN (-6075 4925);
DISPLAY INVISIBLE (-6075 4925);
FORCEPROP 1 LAST HDL_TAP TRUE
J 0
(-5750 4750);
DISPLAY 0.872340 (-5750 4750);
DISPLAY INVISIBLE (-5750 4750);
FORCEPROP 1 LAST PATH I239
J 0
(-6077 4875);
DISPLAY 0.872340 (-6077 4875);
PAINT GREEN (-6077 4875);
DISPLAY INVISIBLE (-6077 4875);
FORCEADD TAP..1
(-6075 4675);
FORCEPROP 3 LASTPIN (-6125 4675) SIG_NAME M_F_CPU0_SA_DQ<10>
J 0
(-6115 4685);
DISPLAY 0.659574 (-6115 4685);
PAINT MONO (-6115 4685);
DISPLAY INVISIBLE (-6115 4685);
FORCEPROP 1 LASTPIN (-6125 4675) BN 10
J 0
(-6137 4683);
DISPLAY 0.489362 (-6137 4683);
PAINT GREEN (-6137 4683);
FORCEPROP 2 LAST CDS_LIB mstr_standard
J 0
(-6075 4675);
DISPLAY 0.723404 (-6075 4675);
PAINT MONO (-6075 4675);
DISPLAY INVISIBLE (-6075 4675);
FORCEPROP 1 LAST BODY_TYPE PLUMBING
J 0
(-6075 4725);
DISPLAY 0.872340 (-6075 4725);
PAINT GREEN (-6075 4725);
DISPLAY INVISIBLE (-6075 4725);
FORCEPROP 1 LAST HDL_TAP TRUE
J 0
(-5750 4550);
DISPLAY 0.872340 (-5750 4550);
DISPLAY INVISIBLE (-5750 4550);
FORCEPROP 1 LAST PATH I240
J 0
(-6077 4675);
DISPLAY 0.872340 (-6077 4675);
PAINT GREEN (-6077 4675);
DISPLAY INVISIBLE (-6077 4675);
FORCEADD TAP..1
(-6075 4625);
FORCEPROP 3 LASTPIN (-6125 4625) SIG_NAME M_F_CPU0_SA_DQ<9>
J 0
(-6115 4635);
DISPLAY 0.659574 (-6115 4635);
PAINT MONO (-6115 4635);
DISPLAY INVISIBLE (-6115 4635);
FORCEPROP 1 LASTPIN (-6125 4625) BN 9
J 0
(-6137 4633);
DISPLAY 0.489362 (-6137 4633);
PAINT GREEN (-6137 4633);
FORCEPROP 2 LAST CDS_LIB mstr_standard
J 0
(-6075 4625);
DISPLAY 0.723404 (-6075 4625);
PAINT MONO (-6075 4625);
DISPLAY INVISIBLE (-6075 4625);
FORCEPROP 1 LAST BODY_TYPE PLUMBING
J 0
(-6075 4675);
DISPLAY 0.872340 (-6075 4675);
PAINT GREEN (-6075 4675);
DISPLAY INVISIBLE (-6075 4675);
FORCEPROP 1 LAST HDL_TAP TRUE
J 0
(-5750 4500);
DISPLAY 0.872340 (-5750 4500);
DISPLAY INVISIBLE (-5750 4500);
FORCEPROP 1 LAST PATH I241
J 0
(-6077 4625);
DISPLAY 0.872340 (-6077 4625);
PAINT GREEN (-6077 4625);
DISPLAY INVISIBLE (-6077 4625);
FORCEADD TAP..1
(-6075 4575);
FORCEPROP 3 LASTPIN (-6125 4575) SIG_NAME M_F_CPU0_SA_DQ<8>
J 0
(-6115 4585);
DISPLAY 0.659574 (-6115 4585);
PAINT MONO (-6115 4585);
DISPLAY INVISIBLE (-6115 4585);
FORCEPROP 1 LASTPIN (-6125 4575) BN 8
J 0
(-6137 4583);
DISPLAY 0.489362 (-6137 4583);
PAINT GREEN (-6137 4583);
FORCEPROP 2 LAST CDS_LIB mstr_standard
J 0
(-6075 4575);
DISPLAY 0.723404 (-6075 4575);
PAINT MONO (-6075 4575);
DISPLAY INVISIBLE (-6075 4575);
FORCEPROP 1 LAST BODY_TYPE PLUMBING
J 0
(-6075 4625);
DISPLAY 0.872340 (-6075 4625);
PAINT GREEN (-6075 4625);
DISPLAY INVISIBLE (-6075 4625);
FORCEPROP 1 LAST HDL_TAP TRUE
J 0
(-5750 4450);
DISPLAY 0.872340 (-5750 4450);
DISPLAY INVISIBLE (-5750 4450);
FORCEPROP 1 LAST PATH I242
J 0
(-6077 4575);
DISPLAY 0.872340 (-6077 4575);
PAINT GREEN (-6077 4575);
DISPLAY INVISIBLE (-6077 4575);
FORCEADD TAP..1
(-6075 4475);
FORCEPROP 3 LASTPIN (-6125 4475) SIG_NAME M_F_CPU0_SA_DQ<6>
J 0
(-6115 4485);
DISPLAY 0.659574 (-6115 4485);
PAINT MONO (-6115 4485);
DISPLAY INVISIBLE (-6115 4485);
FORCEPROP 1 LASTPIN (-6125 4475) BN 6
J 0
(-6137 4483);
DISPLAY 0.489362 (-6137 4483);
PAINT GREEN (-6137 4483);
FORCEPROP 2 LAST CDS_LIB mstr_standard
J 0
(-6075 4475);
DISPLAY 0.723404 (-6075 4475);
PAINT MONO (-6075 4475);
DISPLAY INVISIBLE (-6075 4475);
FORCEPROP 1 LAST BODY_TYPE PLUMBING
J 0
(-6075 4525);
DISPLAY 0.872340 (-6075 4525);
PAINT GREEN (-6075 4525);
DISPLAY INVISIBLE (-6075 4525);
FORCEPROP 1 LAST HDL_TAP TRUE
J 0
(-5750 4350);
DISPLAY 0.872340 (-5750 4350);
DISPLAY INVISIBLE (-5750 4350);
FORCEPROP 1 LAST PATH I243
J 0
(-6077 4475);
DISPLAY 0.872340 (-6077 4475);
PAINT GREEN (-6077 4475);
DISPLAY INVISIBLE (-6077 4475);
FORCEADD TAP..1
(-6075 4525);
FORCEPROP 3 LASTPIN (-6125 4525) SIG_NAME M_F_CPU0_SA_DQ<7>
J 0
(-6115 4535);
DISPLAY 0.659574 (-6115 4535);
PAINT MONO (-6115 4535);
DISPLAY INVISIBLE (-6115 4535);
FORCEPROP 1 LASTPIN (-6125 4525) BN 7
J 0
(-6137 4533);
DISPLAY 0.489362 (-6137 4533);
PAINT GREEN (-6137 4533);
FORCEPROP 2 LAST CDS_LIB mstr_standard
J 0
(-6075 4525);
DISPLAY 0.723404 (-6075 4525);
PAINT MONO (-6075 4525);
DISPLAY INVISIBLE (-6075 4525);
FORCEPROP 1 LAST BODY_TYPE PLUMBING
J 0
(-6075 4575);
DISPLAY 0.872340 (-6075 4575);
PAINT GREEN (-6075 4575);
DISPLAY INVISIBLE (-6075 4575);
FORCEPROP 1 LAST HDL_TAP TRUE
J 0
(-5750 4400);
DISPLAY 0.872340 (-5750 4400);
DISPLAY INVISIBLE (-5750 4400);
FORCEPROP 1 LAST PATH I244
J 0
(-6077 4525);
DISPLAY 0.872340 (-6077 4525);
PAINT GREEN (-6077 4525);
DISPLAY INVISIBLE (-6077 4525);
FORCEADD TAP..1
(-6075 4425);
FORCEPROP 3 LASTPIN (-6125 4425) SIG_NAME M_F_CPU0_SA_DQ<5>
J 0
(-6115 4435);
DISPLAY 0.659574 (-6115 4435);
PAINT MONO (-6115 4435);
DISPLAY INVISIBLE (-6115 4435);
FORCEPROP 1 LASTPIN (-6125 4425) BN 5
J 0
(-6137 4433);
DISPLAY 0.489362 (-6137 4433);
PAINT GREEN (-6137 4433);
FORCEPROP 2 LAST CDS_LIB mstr_standard
J 0
(-6075 4425);
DISPLAY 0.723404 (-6075 4425);
PAINT MONO (-6075 4425);
DISPLAY INVISIBLE (-6075 4425);
FORCEPROP 1 LAST BODY_TYPE PLUMBING
J 0
(-6075 4475);
DISPLAY 0.872340 (-6075 4475);
PAINT GREEN (-6075 4475);
DISPLAY INVISIBLE (-6075 4475);
FORCEPROP 1 LAST HDL_TAP TRUE
J 0
(-5750 4300);
DISPLAY 0.872340 (-5750 4300);
DISPLAY INVISIBLE (-5750 4300);
FORCEPROP 1 LAST PATH I245
J 0
(-6077 4425);
DISPLAY 0.872340 (-6077 4425);
PAINT GREEN (-6077 4425);
DISPLAY INVISIBLE (-6077 4425);
FORCEADD TAP..1
(-6075 4375);
FORCEPROP 3 LASTPIN (-6125 4375) SIG_NAME M_F_CPU0_SA_DQ<4>
J 0
(-6115 4385);
DISPLAY 0.659574 (-6115 4385);
PAINT MONO (-6115 4385);
DISPLAY INVISIBLE (-6115 4385);
FORCEPROP 1 LASTPIN (-6125 4375) BN 4
J 0
(-6137 4383);
DISPLAY 0.489362 (-6137 4383);
PAINT GREEN (-6137 4383);
FORCEPROP 2 LAST CDS_LIB mstr_standard
J 0
(-6075 4375);
DISPLAY 0.723404 (-6075 4375);
PAINT MONO (-6075 4375);
DISPLAY INVISIBLE (-6075 4375);
FORCEPROP 1 LAST BODY_TYPE PLUMBING
J 0
(-6075 4425);
DISPLAY 0.872340 (-6075 4425);
PAINT GREEN (-6075 4425);
DISPLAY INVISIBLE (-6075 4425);
FORCEPROP 1 LAST HDL_TAP TRUE
J 0
(-5750 4250);
DISPLAY 0.872340 (-5750 4250);
DISPLAY INVISIBLE (-5750 4250);
FORCEPROP 1 LAST PATH I246
J 0
(-6077 4375);
DISPLAY 0.872340 (-6077 4375);
PAINT GREEN (-6077 4375);
DISPLAY INVISIBLE (-6077 4375);
FORCEADD TAP..1
(-6075 4325);
FORCEPROP 3 LASTPIN (-6125 4325) SIG_NAME M_F_CPU0_SA_DQ<3>
J 0
(-6115 4335);
DISPLAY 0.659574 (-6115 4335);
PAINT MONO (-6115 4335);
DISPLAY INVISIBLE (-6115 4335);
FORCEPROP 1 LASTPIN (-6125 4325) BN 3
J 0
(-6137 4333);
DISPLAY 0.489362 (-6137 4333);
PAINT GREEN (-6137 4333);
FORCEPROP 2 LAST CDS_LIB mstr_standard
J 0
(-6075 4325);
DISPLAY 0.723404 (-6075 4325);
PAINT MONO (-6075 4325);
DISPLAY INVISIBLE (-6075 4325);
FORCEPROP 1 LAST BODY_TYPE PLUMBING
J 0
(-6075 4375);
DISPLAY 0.872340 (-6075 4375);
PAINT GREEN (-6075 4375);
DISPLAY INVISIBLE (-6075 4375);
FORCEPROP 1 LAST HDL_TAP TRUE
J 0
(-5750 4200);
DISPLAY 0.872340 (-5750 4200);
DISPLAY INVISIBLE (-5750 4200);
FORCEPROP 1 LAST PATH I247
J 0
(-6077 4325);
DISPLAY 0.872340 (-6077 4325);
PAINT GREEN (-6077 4325);
DISPLAY INVISIBLE (-6077 4325);
FORCEADD TAP..1
(-6075 4225);
FORCEPROP 3 LASTPIN (-6125 4225) SIG_NAME M_F_CPU0_SA_DQ<1>
J 0
(-6115 4235);
DISPLAY 0.659574 (-6115 4235);
PAINT MONO (-6115 4235);
DISPLAY INVISIBLE (-6115 4235);
FORCEPROP 1 LASTPIN (-6125 4225) BN 1
J 0
(-6137 4233);
DISPLAY 0.489362 (-6137 4233);
PAINT GREEN (-6137 4233);
FORCEPROP 2 LAST CDS_LIB mstr_standard
J 0
(-6075 4225);
DISPLAY 0.723404 (-6075 4225);
PAINT MONO (-6075 4225);
DISPLAY INVISIBLE (-6075 4225);
FORCEPROP 1 LAST BODY_TYPE PLUMBING
J 0
(-6075 4275);
DISPLAY 0.872340 (-6075 4275);
PAINT GREEN (-6075 4275);
DISPLAY INVISIBLE (-6075 4275);
FORCEPROP 1 LAST HDL_TAP TRUE
J 0
(-5750 4100);
DISPLAY 0.872340 (-5750 4100);
DISPLAY INVISIBLE (-5750 4100);
FORCEPROP 1 LAST PATH I248
J 0
(-6077 4225);
DISPLAY 0.872340 (-6077 4225);
PAINT GREEN (-6077 4225);
DISPLAY INVISIBLE (-6077 4225);
FORCEADD TAP..1
(-6075 4275);
FORCEPROP 3 LASTPIN (-6125 4275) SIG_NAME M_F_CPU0_SA_DQ<2>
J 0
(-6115 4285);
DISPLAY 0.659574 (-6115 4285);
PAINT MONO (-6115 4285);
DISPLAY INVISIBLE (-6115 4285);
FORCEPROP 1 LASTPIN (-6125 4275) BN 2
J 0
(-6137 4283);
DISPLAY 0.489362 (-6137 4283);
PAINT GREEN (-6137 4283);
FORCEPROP 2 LAST CDS_LIB mstr_standard
J 0
(-6075 4275);
DISPLAY 0.723404 (-6075 4275);
PAINT MONO (-6075 4275);
DISPLAY INVISIBLE (-6075 4275);
FORCEPROP 1 LAST BODY_TYPE PLUMBING
J 0
(-6075 4325);
DISPLAY 0.872340 (-6075 4325);
PAINT GREEN (-6075 4325);
DISPLAY INVISIBLE (-6075 4325);
FORCEPROP 1 LAST HDL_TAP TRUE
J 0
(-5750 4150);
DISPLAY 0.872340 (-5750 4150);
DISPLAY INVISIBLE (-5750 4150);
FORCEPROP 1 LAST PATH I249
J 0
(-6077 4275);
DISPLAY 0.872340 (-6077 4275);
PAINT GREEN (-6077 4275);
DISPLAY INVISIBLE (-6077 4275);
FORCEADD TAP..1
(-6075 3975);
FORCEPROP 3 LASTPIN (-6125 3975) SIG_NAME M_F_CPU0_SB_DQ<29>
J 0
(-6115 3985);
DISPLAY 0.659574 (-6115 3985);
PAINT MONO (-6115 3985);
DISPLAY INVISIBLE (-6115 3985);
FORCEPROP 1 LASTPIN (-6125 3975) BN 29
J 0
(-6137 3983);
DISPLAY 0.489362 (-6137 3983);
PAINT GREEN (-6137 3983);
FORCEPROP 2 LAST CDS_LIB mstr_standard
J 0
(-6075 3975);
DISPLAY 0.723404 (-6075 3975);
PAINT MONO (-6075 3975);
DISPLAY INVISIBLE (-6075 3975);
FORCEPROP 1 LAST BODY_TYPE PLUMBING
J 0
(-6075 4025);
DISPLAY 0.872340 (-6075 4025);
PAINT GREEN (-6075 4025);
DISPLAY INVISIBLE (-6075 4025);
FORCEPROP 1 LAST HDL_TAP TRUE
J 0
(-5750 3850);
DISPLAY 0.872340 (-5750 3850);
DISPLAY INVISIBLE (-5750 3850);
FORCEPROP 1 LAST PATH I250
J 0
(-6077 3975);
DISPLAY 0.872340 (-6077 3975);
PAINT GREEN (-6077 3975);
DISPLAY INVISIBLE (-6077 3975);
FORCEADD TAP..1
(-6075 4075);
FORCEPROP 3 LASTPIN (-6125 4075) SIG_NAME M_F_CPU0_SB_DQ<31>
J 0
(-6115 4085);
DISPLAY 0.659574 (-6115 4085);
PAINT MONO (-6115 4085);
DISPLAY INVISIBLE (-6115 4085);
FORCEPROP 1 LASTPIN (-6125 4075) BN 31
J 0
(-6137 4083);
DISPLAY 0.489362 (-6137 4083);
PAINT GREEN (-6137 4083);
FORCEPROP 2 LAST CDS_LIB mstr_standard
J 0
(-6075 4075);
DISPLAY 0.723404 (-6075 4075);
PAINT MONO (-6075 4075);
DISPLAY INVISIBLE (-6075 4075);
FORCEPROP 1 LAST BODY_TYPE PLUMBING
J 0
(-6075 4125);
DISPLAY 0.872340 (-6075 4125);
PAINT GREEN (-6075 4125);
DISPLAY INVISIBLE (-6075 4125);
FORCEPROP 1 LAST HDL_TAP TRUE
J 0
(-5750 3950);
DISPLAY 0.872340 (-5750 3950);
DISPLAY INVISIBLE (-5750 3950);
FORCEPROP 1 LAST PATH I251
J 0
(-6077 4075);
DISPLAY 0.872340 (-6077 4075);
PAINT GREEN (-6077 4075);
DISPLAY INVISIBLE (-6077 4075);
FORCEADD TAP..1
(-6075 4025);
FORCEPROP 3 LASTPIN (-6125 4025) SIG_NAME M_F_CPU0_SB_DQ<30>
J 0
(-6115 4035);
DISPLAY 0.659574 (-6115 4035);
PAINT MONO (-6115 4035);
DISPLAY INVISIBLE (-6115 4035);
FORCEPROP 1 LASTPIN (-6125 4025) BN 30
J 0
(-6137 4033);
DISPLAY 0.489362 (-6137 4033);
PAINT GREEN (-6137 4033);
FORCEPROP 2 LAST CDS_LIB mstr_standard
J 0
(-6075 4025);
DISPLAY 0.723404 (-6075 4025);
PAINT MONO (-6075 4025);
DISPLAY INVISIBLE (-6075 4025);
FORCEPROP 1 LAST BODY_TYPE PLUMBING
J 0
(-6075 4075);
DISPLAY 0.872340 (-6075 4075);
PAINT GREEN (-6075 4075);
DISPLAY INVISIBLE (-6075 4075);
FORCEPROP 1 LAST HDL_TAP TRUE
J 0
(-5750 3900);
DISPLAY 0.872340 (-5750 3900);
DISPLAY INVISIBLE (-5750 3900);
FORCEPROP 1 LAST PATH I252
J 0
(-6077 4025);
DISPLAY 0.872340 (-6077 4025);
PAINT GREEN (-6077 4025);
DISPLAY INVISIBLE (-6077 4025);
FORCEADD TAP..1
(-6075 4175);
FORCEPROP 3 LASTPIN (-6125 4175) SIG_NAME M_F_CPU0_SA_DQ<0>
J 0
(-6115 4185);
DISPLAY 0.659574 (-6115 4185);
PAINT MONO (-6115 4185);
DISPLAY INVISIBLE (-6115 4185);
FORCEPROP 1 LASTPIN (-6125 4175) BN 0
J 0
(-6137 4183);
DISPLAY 0.489362 (-6137 4183);
PAINT GREEN (-6137 4183);
FORCEPROP 2 LAST CDS_LIB mstr_standard
J 0
(-6075 4175);
DISPLAY 0.723404 (-6075 4175);
PAINT MONO (-6075 4175);
DISPLAY INVISIBLE (-6075 4175);
FORCEPROP 1 LAST BODY_TYPE PLUMBING
J 0
(-6075 4225);
DISPLAY 0.872340 (-6075 4225);
PAINT GREEN (-6075 4225);
DISPLAY INVISIBLE (-6075 4225);
FORCEPROP 1 LAST HDL_TAP TRUE
J 0
(-5750 4050);
DISPLAY 0.872340 (-5750 4050);
DISPLAY INVISIBLE (-5750 4050);
FORCEPROP 1 LAST PATH I253
J 0
(-6077 4175);
DISPLAY 0.872340 (-6077 4175);
PAINT GREEN (-6077 4175);
DISPLAY INVISIBLE (-6077 4175);
FORCEADD TAP..1
(-6075 3725);
FORCEPROP 3 LASTPIN (-6125 3725) SIG_NAME M_F_CPU0_SB_DQ<24>
J 0
(-6115 3735);
DISPLAY 0.659574 (-6115 3735);
PAINT MONO (-6115 3735);
DISPLAY INVISIBLE (-6115 3735);
FORCEPROP 1 LASTPIN (-6125 3725) BN 24
J 0
(-6137 3733);
DISPLAY 0.489362 (-6137 3733);
PAINT GREEN (-6137 3733);
FORCEPROP 2 LAST CDS_LIB mstr_standard
J 0
(-6075 3725);
DISPLAY 0.723404 (-6075 3725);
PAINT MONO (-6075 3725);
DISPLAY INVISIBLE (-6075 3725);
FORCEPROP 1 LAST BODY_TYPE PLUMBING
J 0
(-6075 3775);
DISPLAY 0.872340 (-6075 3775);
PAINT GREEN (-6075 3775);
DISPLAY INVISIBLE (-6075 3775);
FORCEPROP 1 LAST HDL_TAP TRUE
J 0
(-5750 3600);
DISPLAY 0.872340 (-5750 3600);
DISPLAY INVISIBLE (-5750 3600);
FORCEPROP 1 LAST PATH I254
J 0
(-6077 3725);
DISPLAY 0.872340 (-6077 3725);
PAINT GREEN (-6077 3725);
DISPLAY INVISIBLE (-6077 3725);
FORCEADD TAP..1
(-6075 3925);
FORCEPROP 3 LASTPIN (-6125 3925) SIG_NAME M_F_CPU0_SB_DQ<28>
J 0
(-6115 3935);
DISPLAY 0.659574 (-6115 3935);
PAINT MONO (-6115 3935);
DISPLAY INVISIBLE (-6115 3935);
FORCEPROP 1 LASTPIN (-6125 3925) BN 28
J 0
(-6137 3933);
DISPLAY 0.489362 (-6137 3933);
PAINT GREEN (-6137 3933);
FORCEPROP 2 LAST CDS_LIB mstr_standard
J 0
(-6075 3925);
DISPLAY 0.723404 (-6075 3925);
PAINT MONO (-6075 3925);
DISPLAY INVISIBLE (-6075 3925);
FORCEPROP 1 LAST BODY_TYPE PLUMBING
J 0
(-6075 3975);
DISPLAY 0.872340 (-6075 3975);
PAINT GREEN (-6075 3975);
DISPLAY INVISIBLE (-6075 3975);
FORCEPROP 1 LAST HDL_TAP TRUE
J 0
(-5750 3800);
DISPLAY 0.872340 (-5750 3800);
DISPLAY INVISIBLE (-5750 3800);
FORCEPROP 1 LAST PATH I255
J 0
(-6077 3925);
DISPLAY 0.872340 (-6077 3925);
PAINT GREEN (-6077 3925);
DISPLAY INVISIBLE (-6077 3925);
FORCEADD TAP..1
(-6075 3775);
FORCEPROP 3 LASTPIN (-6125 3775) SIG_NAME M_F_CPU0_SB_DQ<25>
J 0
(-6115 3785);
DISPLAY 0.659574 (-6115 3785);
PAINT MONO (-6115 3785);
DISPLAY INVISIBLE (-6115 3785);
FORCEPROP 1 LASTPIN (-6125 3775) BN 25
J 0
(-6137 3783);
DISPLAY 0.489362 (-6137 3783);
PAINT GREEN (-6137 3783);
FORCEPROP 2 LAST CDS_LIB mstr_standard
J 0
(-6075 3775);
DISPLAY 0.723404 (-6075 3775);
PAINT MONO (-6075 3775);
DISPLAY INVISIBLE (-6075 3775);
FORCEPROP 1 LAST BODY_TYPE PLUMBING
J 0
(-6075 3825);
DISPLAY 0.872340 (-6075 3825);
PAINT GREEN (-6075 3825);
DISPLAY INVISIBLE (-6075 3825);
FORCEPROP 1 LAST HDL_TAP TRUE
J 0
(-5750 3650);
DISPLAY 0.872340 (-5750 3650);
DISPLAY INVISIBLE (-5750 3650);
FORCEPROP 1 LAST PATH I256
J 0
(-6077 3775);
DISPLAY 0.872340 (-6077 3775);
PAINT GREEN (-6077 3775);
DISPLAY INVISIBLE (-6077 3775);
FORCEADD TAP..1
(-6075 3875);
FORCEPROP 3 LASTPIN (-6125 3875) SIG_NAME M_F_CPU0_SB_DQ<27>
J 0
(-6115 3885);
DISPLAY 0.659574 (-6115 3885);
PAINT MONO (-6115 3885);
DISPLAY INVISIBLE (-6115 3885);
FORCEPROP 1 LASTPIN (-6125 3875) BN 27
J 0
(-6137 3883);
DISPLAY 0.489362 (-6137 3883);
PAINT GREEN (-6137 3883);
FORCEPROP 2 LAST CDS_LIB mstr_standard
J 0
(-6075 3875);
DISPLAY 0.723404 (-6075 3875);
PAINT MONO (-6075 3875);
DISPLAY INVISIBLE (-6075 3875);
FORCEPROP 1 LAST BODY_TYPE PLUMBING
J 0
(-6075 3925);
DISPLAY 0.872340 (-6075 3925);
PAINT GREEN (-6075 3925);
DISPLAY INVISIBLE (-6075 3925);
FORCEPROP 1 LAST HDL_TAP TRUE
J 0
(-5750 3750);
DISPLAY 0.872340 (-5750 3750);
DISPLAY INVISIBLE (-5750 3750);
FORCEPROP 1 LAST PATH I257
J 0
(-6077 3875);
DISPLAY 0.872340 (-6077 3875);
PAINT GREEN (-6077 3875);
DISPLAY INVISIBLE (-6077 3875);
FORCEADD TAP..1
(-6075 3825);
FORCEPROP 3 LASTPIN (-6125 3825) SIG_NAME M_F_CPU0_SB_DQ<26>
J 0
(-6115 3835);
DISPLAY 0.659574 (-6115 3835);
PAINT MONO (-6115 3835);
DISPLAY INVISIBLE (-6115 3835);
FORCEPROP 1 LASTPIN (-6125 3825) BN 26
J 0
(-6137 3833);
DISPLAY 0.489362 (-6137 3833);
PAINT GREEN (-6137 3833);
FORCEPROP 2 LAST CDS_LIB mstr_standard
J 0
(-6075 3825);
DISPLAY 0.723404 (-6075 3825);
PAINT MONO (-6075 3825);
DISPLAY INVISIBLE (-6075 3825);
FORCEPROP 1 LAST BODY_TYPE PLUMBING
J 0
(-6075 3875);
DISPLAY 0.872340 (-6075 3875);
PAINT GREEN (-6075 3875);
DISPLAY INVISIBLE (-6075 3875);
FORCEPROP 1 LAST HDL_TAP TRUE
J 0
(-5750 3700);
DISPLAY 0.872340 (-5750 3700);
DISPLAY INVISIBLE (-5750 3700);
FORCEPROP 1 LAST PATH I258
J 0
(-6077 3825);
DISPLAY 0.872340 (-6077 3825);
PAINT GREEN (-6077 3825);
DISPLAY INVISIBLE (-6077 3825);
FORCEADD TAP..1
(-6075 3475);
FORCEPROP 3 LASTPIN (-6125 3475) SIG_NAME M_F_CPU0_SB_DQ<19>
J 0
(-6115 3485);
DISPLAY 0.659574 (-6115 3485);
PAINT MONO (-6115 3485);
DISPLAY INVISIBLE (-6115 3485);
FORCEPROP 1 LASTPIN (-6125 3475) BN 19
J 0
(-6137 3483);
DISPLAY 0.489362 (-6137 3483);
PAINT GREEN (-6137 3483);
FORCEPROP 2 LAST CDS_LIB mstr_standard
J 0
(-6075 3475);
DISPLAY 0.723404 (-6075 3475);
PAINT MONO (-6075 3475);
DISPLAY INVISIBLE (-6075 3475);
FORCEPROP 1 LAST BODY_TYPE PLUMBING
J 0
(-6075 3525);
DISPLAY 0.872340 (-6075 3525);
PAINT GREEN (-6075 3525);
DISPLAY INVISIBLE (-6075 3525);
FORCEPROP 1 LAST HDL_TAP TRUE
J 0
(-5750 3350);
DISPLAY 0.872340 (-5750 3350);
DISPLAY INVISIBLE (-5750 3350);
FORCEPROP 1 LAST PATH I259
J 0
(-6077 3475);
DISPLAY 0.872340 (-6077 3475);
PAINT GREEN (-6077 3475);
DISPLAY INVISIBLE (-6077 3475);
FORCEADD TAP..1
(-6075 3675);
FORCEPROP 3 LASTPIN (-6125 3675) SIG_NAME M_F_CPU0_SB_DQ<23>
J 0
(-6115 3685);
DISPLAY 0.659574 (-6115 3685);
PAINT MONO (-6115 3685);
DISPLAY INVISIBLE (-6115 3685);
FORCEPROP 1 LASTPIN (-6125 3675) BN 23
J 0
(-6137 3683);
DISPLAY 0.489362 (-6137 3683);
PAINT GREEN (-6137 3683);
FORCEPROP 2 LAST CDS_LIB mstr_standard
J 0
(-6075 3675);
DISPLAY 0.723404 (-6075 3675);
PAINT MONO (-6075 3675);
DISPLAY INVISIBLE (-6075 3675);
FORCEPROP 1 LAST BODY_TYPE PLUMBING
J 0
(-6075 3725);
DISPLAY 0.872340 (-6075 3725);
PAINT GREEN (-6075 3725);
DISPLAY INVISIBLE (-6075 3725);
FORCEPROP 1 LAST HDL_TAP TRUE
J 0
(-5750 3550);
DISPLAY 0.872340 (-5750 3550);
DISPLAY INVISIBLE (-5750 3550);
FORCEPROP 1 LAST PATH I260
J 0
(-6077 3675);
DISPLAY 0.872340 (-6077 3675);
PAINT GREEN (-6077 3675);
DISPLAY INVISIBLE (-6077 3675);
FORCEADD TAP..1
(-6075 3525);
FORCEPROP 3 LASTPIN (-6125 3525) SIG_NAME M_F_CPU0_SB_DQ<20>
J 0
(-6115 3535);
DISPLAY 0.659574 (-6115 3535);
PAINT MONO (-6115 3535);
DISPLAY INVISIBLE (-6115 3535);
FORCEPROP 1 LASTPIN (-6125 3525) BN 20
J 0
(-6137 3533);
DISPLAY 0.489362 (-6137 3533);
PAINT GREEN (-6137 3533);
FORCEPROP 2 LAST CDS_LIB mstr_standard
J 0
(-6075 3525);
DISPLAY 0.723404 (-6075 3525);
PAINT MONO (-6075 3525);
DISPLAY INVISIBLE (-6075 3525);
FORCEPROP 1 LAST BODY_TYPE PLUMBING
J 0
(-6075 3575);
DISPLAY 0.872340 (-6075 3575);
PAINT GREEN (-6075 3575);
DISPLAY INVISIBLE (-6075 3575);
FORCEPROP 1 LAST HDL_TAP TRUE
J 0
(-5750 3400);
DISPLAY 0.872340 (-5750 3400);
DISPLAY INVISIBLE (-5750 3400);
FORCEPROP 1 LAST PATH I261
J 0
(-6077 3525);
DISPLAY 0.872340 (-6077 3525);
PAINT GREEN (-6077 3525);
DISPLAY INVISIBLE (-6077 3525);
FORCEADD TAP..1
(-6075 3625);
FORCEPROP 3 LASTPIN (-6125 3625) SIG_NAME M_F_CPU0_SB_DQ<22>
J 0
(-6115 3635);
DISPLAY 0.659574 (-6115 3635);
PAINT MONO (-6115 3635);
DISPLAY INVISIBLE (-6115 3635);
FORCEPROP 1 LASTPIN (-6125 3625) BN 22
J 0
(-6137 3633);
DISPLAY 0.489362 (-6137 3633);
PAINT GREEN (-6137 3633);
FORCEPROP 2 LAST CDS_LIB mstr_standard
J 0
(-6075 3625);
DISPLAY 0.723404 (-6075 3625);
PAINT MONO (-6075 3625);
DISPLAY INVISIBLE (-6075 3625);
FORCEPROP 1 LAST BODY_TYPE PLUMBING
J 0
(-6075 3675);
DISPLAY 0.872340 (-6075 3675);
PAINT GREEN (-6075 3675);
DISPLAY INVISIBLE (-6075 3675);
FORCEPROP 1 LAST HDL_TAP TRUE
J 0
(-5750 3500);
DISPLAY 0.872340 (-5750 3500);
DISPLAY INVISIBLE (-5750 3500);
FORCEPROP 1 LAST PATH I262
J 0
(-6077 3625);
DISPLAY 0.872340 (-6077 3625);
PAINT GREEN (-6077 3625);
DISPLAY INVISIBLE (-6077 3625);
FORCEADD TAP..1
(-6075 3575);
FORCEPROP 3 LASTPIN (-6125 3575) SIG_NAME M_F_CPU0_SB_DQ<21>
J 0
(-6115 3585);
DISPLAY 0.659574 (-6115 3585);
PAINT MONO (-6115 3585);
DISPLAY INVISIBLE (-6115 3585);
FORCEPROP 1 LASTPIN (-6125 3575) BN 21
J 0
(-6137 3583);
DISPLAY 0.489362 (-6137 3583);
PAINT GREEN (-6137 3583);
FORCEPROP 2 LAST CDS_LIB mstr_standard
J 0
(-6075 3575);
DISPLAY 0.723404 (-6075 3575);
PAINT MONO (-6075 3575);
DISPLAY INVISIBLE (-6075 3575);
FORCEPROP 1 LAST BODY_TYPE PLUMBING
J 0
(-6075 3625);
DISPLAY 0.872340 (-6075 3625);
PAINT GREEN (-6075 3625);
DISPLAY INVISIBLE (-6075 3625);
FORCEPROP 1 LAST HDL_TAP TRUE
J 0
(-5750 3450);
DISPLAY 0.872340 (-5750 3450);
DISPLAY INVISIBLE (-5750 3450);
FORCEPROP 1 LAST PATH I263
J 0
(-6077 3575);
DISPLAY 0.872340 (-6077 3575);
PAINT GREEN (-6077 3575);
DISPLAY INVISIBLE (-6077 3575);
FORCEADD TAP..1
(-6075 3325);
FORCEPROP 3 LASTPIN (-6125 3325) SIG_NAME M_F_CPU0_SB_DQ<16>
J 0
(-6115 3335);
DISPLAY 0.659574 (-6115 3335);
PAINT MONO (-6115 3335);
DISPLAY INVISIBLE (-6115 3335);
FORCEPROP 1 LASTPIN (-6125 3325) BN 16
J 0
(-6137 3333);
DISPLAY 0.489362 (-6137 3333);
PAINT GREEN (-6137 3333);
FORCEPROP 2 LAST CDS_LIB mstr_standard
J 0
(-6075 3325);
DISPLAY 0.723404 (-6075 3325);
PAINT MONO (-6075 3325);
DISPLAY INVISIBLE (-6075 3325);
FORCEPROP 1 LAST BODY_TYPE PLUMBING
J 0
(-6075 3375);
DISPLAY 0.872340 (-6075 3375);
PAINT GREEN (-6075 3375);
DISPLAY INVISIBLE (-6075 3375);
FORCEPROP 1 LAST HDL_TAP TRUE
J 0
(-5750 3200);
DISPLAY 0.872340 (-5750 3200);
DISPLAY INVISIBLE (-5750 3200);
FORCEPROP 1 LAST PATH I264
J 0
(-6077 3325);
DISPLAY 0.872340 (-6077 3325);
PAINT GREEN (-6077 3325);
DISPLAY INVISIBLE (-6077 3325);
FORCEADD TAP..1
(-6075 3375);
FORCEPROP 3 LASTPIN (-6125 3375) SIG_NAME M_F_CPU0_SB_DQ<17>
J 0
(-6115 3385);
DISPLAY 0.659574 (-6115 3385);
PAINT MONO (-6115 3385);
DISPLAY INVISIBLE (-6115 3385);
FORCEPROP 1 LASTPIN (-6125 3375) BN 17
J 0
(-6137 3383);
DISPLAY 0.489362 (-6137 3383);
PAINT GREEN (-6137 3383);
FORCEPROP 2 LAST CDS_LIB mstr_standard
J 0
(-6075 3375);
DISPLAY 0.723404 (-6075 3375);
PAINT MONO (-6075 3375);
DISPLAY INVISIBLE (-6075 3375);
FORCEPROP 1 LAST BODY_TYPE PLUMBING
J 0
(-6075 3425);
DISPLAY 0.872340 (-6075 3425);
PAINT GREEN (-6075 3425);
DISPLAY INVISIBLE (-6075 3425);
FORCEPROP 1 LAST HDL_TAP TRUE
J 0
(-5750 3250);
DISPLAY 0.872340 (-5750 3250);
DISPLAY INVISIBLE (-5750 3250);
FORCEPROP 1 LAST PATH I265
J 0
(-6077 3375);
DISPLAY 0.872340 (-6077 3375);
PAINT GREEN (-6077 3375);
DISPLAY INVISIBLE (-6077 3375);
FORCEADD TAP..1
(-6075 3425);
FORCEPROP 3 LASTPIN (-6125 3425) SIG_NAME M_F_CPU0_SB_DQ<18>
J 0
(-6115 3435);
DISPLAY 0.659574 (-6115 3435);
PAINT MONO (-6115 3435);
DISPLAY INVISIBLE (-6115 3435);
FORCEPROP 1 LASTPIN (-6125 3425) BN 18
J 0
(-6137 3433);
DISPLAY 0.489362 (-6137 3433);
PAINT GREEN (-6137 3433);
FORCEPROP 2 LAST CDS_LIB mstr_standard
J 0
(-6075 3425);
DISPLAY 0.723404 (-6075 3425);
PAINT MONO (-6075 3425);
DISPLAY INVISIBLE (-6075 3425);
FORCEPROP 1 LAST BODY_TYPE PLUMBING
J 0
(-6075 3475);
DISPLAY 0.872340 (-6075 3475);
PAINT GREEN (-6075 3475);
DISPLAY INVISIBLE (-6075 3475);
FORCEPROP 1 LAST HDL_TAP TRUE
J 0
(-5750 3300);
DISPLAY 0.872340 (-5750 3300);
DISPLAY INVISIBLE (-5750 3300);
FORCEPROP 1 LAST PATH I266
J 0
(-6077 3425);
DISPLAY 0.872340 (-6077 3425);
PAINT GREEN (-6077 3425);
DISPLAY INVISIBLE (-6077 3425);
FORCEADD TAP..1
(-6075 3225);
FORCEPROP 3 LASTPIN (-6125 3225) SIG_NAME M_F_CPU0_SB_DQ<14>
J 0
(-6115 3235);
DISPLAY 0.659574 (-6115 3235);
PAINT MONO (-6115 3235);
DISPLAY INVISIBLE (-6115 3235);
FORCEPROP 1 LASTPIN (-6125 3225) BN 14
J 0
(-6137 3233);
DISPLAY 0.489362 (-6137 3233);
PAINT GREEN (-6137 3233);
FORCEPROP 2 LAST CDS_LIB mstr_standard
J 0
(-6075 3225);
DISPLAY 0.723404 (-6075 3225);
PAINT MONO (-6075 3225);
DISPLAY INVISIBLE (-6075 3225);
FORCEPROP 1 LAST BODY_TYPE PLUMBING
J 0
(-6075 3275);
DISPLAY 0.872340 (-6075 3275);
PAINT GREEN (-6075 3275);
DISPLAY INVISIBLE (-6075 3275);
FORCEPROP 1 LAST HDL_TAP TRUE
J 0
(-5750 3100);
DISPLAY 0.872340 (-5750 3100);
DISPLAY INVISIBLE (-5750 3100);
FORCEPROP 1 LAST PATH I267
J 0
(-6077 3225);
DISPLAY 0.872340 (-6077 3225);
PAINT GREEN (-6077 3225);
DISPLAY INVISIBLE (-6077 3225);
FORCEADD TAP..1
(-6075 3275);
FORCEPROP 3 LASTPIN (-6125 3275) SIG_NAME M_F_CPU0_SB_DQ<15>
J 0
(-6115 3285);
DISPLAY 0.659574 (-6115 3285);
PAINT MONO (-6115 3285);
DISPLAY INVISIBLE (-6115 3285);
FORCEPROP 1 LASTPIN (-6125 3275) BN 15
J 0
(-6137 3283);
DISPLAY 0.489362 (-6137 3283);
PAINT GREEN (-6137 3283);
FORCEPROP 2 LAST CDS_LIB mstr_standard
J 0
(-6075 3275);
DISPLAY 0.723404 (-6075 3275);
PAINT MONO (-6075 3275);
DISPLAY INVISIBLE (-6075 3275);
FORCEPROP 1 LAST BODY_TYPE PLUMBING
J 0
(-6075 3325);
DISPLAY 0.872340 (-6075 3325);
PAINT GREEN (-6075 3325);
DISPLAY INVISIBLE (-6075 3325);
FORCEPROP 1 LAST HDL_TAP TRUE
J 0
(-5750 3150);
DISPLAY 0.872340 (-5750 3150);
DISPLAY INVISIBLE (-5750 3150);
FORCEPROP 1 LAST PATH I268
J 0
(-6077 3275);
DISPLAY 0.872340 (-6077 3275);
PAINT GREEN (-6077 3275);
DISPLAY INVISIBLE (-6077 3275);
FORCEADD TAP..1
(-6075 3175);
FORCEPROP 3 LASTPIN (-6125 3175) SIG_NAME M_F_CPU0_SB_DQ<13>
J 0
(-6115 3185);
DISPLAY 0.659574 (-6115 3185);
PAINT MONO (-6115 3185);
DISPLAY INVISIBLE (-6115 3185);
FORCEPROP 1 LASTPIN (-6125 3175) BN 13
J 0
(-6137 3183);
DISPLAY 0.489362 (-6137 3183);
PAINT GREEN (-6137 3183);
FORCEPROP 2 LAST CDS_LIB mstr_standard
J 0
(-6075 3175);
DISPLAY 0.723404 (-6075 3175);
PAINT MONO (-6075 3175);
DISPLAY INVISIBLE (-6075 3175);
FORCEPROP 1 LAST BODY_TYPE PLUMBING
J 0
(-6075 3225);
DISPLAY 0.872340 (-6075 3225);
PAINT GREEN (-6075 3225);
DISPLAY INVISIBLE (-6075 3225);
FORCEPROP 1 LAST HDL_TAP TRUE
J 0
(-5750 3050);
DISPLAY 0.872340 (-5750 3050);
DISPLAY INVISIBLE (-5750 3050);
FORCEPROP 1 LAST PATH I269
J 0
(-6077 3175);
DISPLAY 0.872340 (-6077 3175);
PAINT GREEN (-6077 3175);
DISPLAY INVISIBLE (-6077 3175);
FORCEADD TAP..1
(-6075 3125);
FORCEPROP 3 LASTPIN (-6125 3125) SIG_NAME M_F_CPU0_SB_DQ<12>
J 0
(-6115 3135);
DISPLAY 0.659574 (-6115 3135);
PAINT MONO (-6115 3135);
DISPLAY INVISIBLE (-6115 3135);
FORCEPROP 1 LASTPIN (-6125 3125) BN 12
J 0
(-6137 3133);
DISPLAY 0.489362 (-6137 3133);
PAINT GREEN (-6137 3133);
FORCEPROP 2 LAST CDS_LIB mstr_standard
J 0
(-6075 3125);
DISPLAY 0.723404 (-6075 3125);
PAINT MONO (-6075 3125);
DISPLAY INVISIBLE (-6075 3125);
FORCEPROP 1 LAST BODY_TYPE PLUMBING
J 0
(-6075 3175);
DISPLAY 0.872340 (-6075 3175);
PAINT GREEN (-6075 3175);
DISPLAY INVISIBLE (-6075 3175);
FORCEPROP 1 LAST HDL_TAP TRUE
J 0
(-5750 3000);
DISPLAY 0.872340 (-5750 3000);
DISPLAY INVISIBLE (-5750 3000);
FORCEPROP 1 LAST PATH I270
J 0
(-6077 3125);
DISPLAY 0.872340 (-6077 3125);
PAINT GREEN (-6077 3125);
DISPLAY INVISIBLE (-6077 3125);
FORCEADD TAP..1
(-6075 3075);
FORCEPROP 3 LASTPIN (-6125 3075) SIG_NAME M_F_CPU0_SB_DQ<11>
J 0
(-6115 3085);
DISPLAY 0.659574 (-6115 3085);
PAINT MONO (-6115 3085);
DISPLAY INVISIBLE (-6115 3085);
FORCEPROP 1 LASTPIN (-6125 3075) BN 11
J 0
(-6137 3083);
DISPLAY 0.489362 (-6137 3083);
PAINT GREEN (-6137 3083);
FORCEPROP 2 LAST CDS_LIB mstr_standard
J 0
(-6075 3075);
DISPLAY 0.723404 (-6075 3075);
PAINT MONO (-6075 3075);
DISPLAY INVISIBLE (-6075 3075);
FORCEPROP 1 LAST BODY_TYPE PLUMBING
J 0
(-6075 3125);
DISPLAY 0.872340 (-6075 3125);
PAINT GREEN (-6075 3125);
DISPLAY INVISIBLE (-6075 3125);
FORCEPROP 1 LAST HDL_TAP TRUE
J 0
(-5750 2950);
DISPLAY 0.872340 (-5750 2950);
DISPLAY INVISIBLE (-5750 2950);
FORCEPROP 1 LAST PATH I271
J 0
(-6077 3075);
DISPLAY 0.872340 (-6077 3075);
PAINT GREEN (-6077 3075);
DISPLAY INVISIBLE (-6077 3075);
FORCEADD TAP..1
(-6075 3025);
FORCEPROP 3 LASTPIN (-6125 3025) SIG_NAME M_F_CPU0_SB_DQ<10>
J 0
(-6115 3035);
DISPLAY 0.659574 (-6115 3035);
PAINT MONO (-6115 3035);
DISPLAY INVISIBLE (-6115 3035);
FORCEPROP 1 LASTPIN (-6125 3025) BN 10
J 0
(-6137 3033);
DISPLAY 0.489362 (-6137 3033);
PAINT GREEN (-6137 3033);
FORCEPROP 2 LAST CDS_LIB mstr_standard
J 0
(-6075 3025);
DISPLAY 0.723404 (-6075 3025);
PAINT MONO (-6075 3025);
DISPLAY INVISIBLE (-6075 3025);
FORCEPROP 1 LAST BODY_TYPE PLUMBING
J 0
(-6075 3075);
DISPLAY 0.872340 (-6075 3075);
PAINT GREEN (-6075 3075);
DISPLAY INVISIBLE (-6075 3075);
FORCEPROP 1 LAST HDL_TAP TRUE
J 0
(-5750 2900);
DISPLAY 0.872340 (-5750 2900);
DISPLAY INVISIBLE (-5750 2900);
FORCEPROP 1 LAST PATH I272
J 0
(-6077 3025);
DISPLAY 0.872340 (-6077 3025);
PAINT GREEN (-6077 3025);
DISPLAY INVISIBLE (-6077 3025);
FORCEADD TAP..1
(-6075 2975);
FORCEPROP 3 LASTPIN (-6125 2975) SIG_NAME M_F_CPU0_SB_DQ<9>
J 0
(-6115 2985);
DISPLAY 0.659574 (-6115 2985);
PAINT MONO (-6115 2985);
DISPLAY INVISIBLE (-6115 2985);
FORCEPROP 1 LASTPIN (-6125 2975) BN 9
J 0
(-6137 2983);
DISPLAY 0.489362 (-6137 2983);
PAINT GREEN (-6137 2983);
FORCEPROP 2 LAST CDS_LIB mstr_standard
J 0
(-6075 2975);
DISPLAY 0.723404 (-6075 2975);
PAINT MONO (-6075 2975);
DISPLAY INVISIBLE (-6075 2975);
FORCEPROP 1 LAST BODY_TYPE PLUMBING
J 0
(-6075 3025);
DISPLAY 0.872340 (-6075 3025);
PAINT GREEN (-6075 3025);
DISPLAY INVISIBLE (-6075 3025);
FORCEPROP 1 LAST HDL_TAP TRUE
J 0
(-5750 2850);
DISPLAY 0.872340 (-5750 2850);
DISPLAY INVISIBLE (-5750 2850);
FORCEPROP 1 LAST PATH I273
J 0
(-6077 2975);
DISPLAY 0.872340 (-6077 2975);
PAINT GREEN (-6077 2975);
DISPLAY INVISIBLE (-6077 2975);
FORCEADD TAP..1
(-6075 2925);
FORCEPROP 3 LASTPIN (-6125 2925) SIG_NAME M_F_CPU0_SB_DQ<8>
J 0
(-6115 2935);
DISPLAY 0.659574 (-6115 2935);
PAINT MONO (-6115 2935);
DISPLAY INVISIBLE (-6115 2935);
FORCEPROP 1 LASTPIN (-6125 2925) BN 8
J 0
(-6137 2933);
DISPLAY 0.489362 (-6137 2933);
PAINT GREEN (-6137 2933);
FORCEPROP 2 LAST CDS_LIB mstr_standard
J 0
(-6075 2925);
DISPLAY 0.723404 (-6075 2925);
PAINT MONO (-6075 2925);
DISPLAY INVISIBLE (-6075 2925);
FORCEPROP 1 LAST BODY_TYPE PLUMBING
J 0
(-6075 2975);
DISPLAY 0.872340 (-6075 2975);
PAINT GREEN (-6075 2975);
DISPLAY INVISIBLE (-6075 2975);
FORCEPROP 1 LAST HDL_TAP TRUE
J 0
(-5750 2800);
DISPLAY 0.872340 (-5750 2800);
DISPLAY INVISIBLE (-5750 2800);
FORCEPROP 1 LAST PATH I274
J 0
(-6077 2925);
DISPLAY 0.872340 (-6077 2925);
PAINT GREEN (-6077 2925);
DISPLAY INVISIBLE (-6077 2925);
FORCEADD TAP..1
(-6075 2825);
FORCEPROP 3 LASTPIN (-6125 2825) SIG_NAME M_F_CPU0_SB_DQ<6>
J 0
(-6115 2835);
DISPLAY 0.659574 (-6115 2835);
PAINT MONO (-6115 2835);
DISPLAY INVISIBLE (-6115 2835);
FORCEPROP 1 LASTPIN (-6125 2825) BN 6
J 0
(-6137 2833);
DISPLAY 0.489362 (-6137 2833);
PAINT GREEN (-6137 2833);
FORCEPROP 2 LAST CDS_LIB mstr_standard
J 0
(-6075 2825);
DISPLAY 0.723404 (-6075 2825);
PAINT MONO (-6075 2825);
DISPLAY INVISIBLE (-6075 2825);
FORCEPROP 1 LAST BODY_TYPE PLUMBING
J 0
(-6075 2875);
DISPLAY 0.872340 (-6075 2875);
PAINT GREEN (-6075 2875);
DISPLAY INVISIBLE (-6075 2875);
FORCEPROP 1 LAST HDL_TAP TRUE
J 0
(-5750 2700);
DISPLAY 0.872340 (-5750 2700);
DISPLAY INVISIBLE (-5750 2700);
FORCEPROP 1 LAST PATH I275
J 0
(-6077 2825);
DISPLAY 0.872340 (-6077 2825);
PAINT GREEN (-6077 2825);
DISPLAY INVISIBLE (-6077 2825);
FORCEADD TAP..1
(-6075 2875);
FORCEPROP 3 LASTPIN (-6125 2875) SIG_NAME M_F_CPU0_SB_DQ<7>
J 0
(-6115 2885);
DISPLAY 0.659574 (-6115 2885);
PAINT MONO (-6115 2885);
DISPLAY INVISIBLE (-6115 2885);
FORCEPROP 1 LASTPIN (-6125 2875) BN 7
J 0
(-6137 2883);
DISPLAY 0.489362 (-6137 2883);
PAINT GREEN (-6137 2883);
FORCEPROP 2 LAST CDS_LIB mstr_standard
J 0
(-6075 2875);
DISPLAY 0.723404 (-6075 2875);
PAINT MONO (-6075 2875);
DISPLAY INVISIBLE (-6075 2875);
FORCEPROP 1 LAST BODY_TYPE PLUMBING
J 0
(-6075 2925);
DISPLAY 0.872340 (-6075 2925);
PAINT GREEN (-6075 2925);
DISPLAY INVISIBLE (-6075 2925);
FORCEPROP 1 LAST HDL_TAP TRUE
J 0
(-5750 2750);
DISPLAY 0.872340 (-5750 2750);
DISPLAY INVISIBLE (-5750 2750);
FORCEPROP 1 LAST PATH I276
J 0
(-6077 2875);
DISPLAY 0.872340 (-6077 2875);
PAINT GREEN (-6077 2875);
DISPLAY INVISIBLE (-6077 2875);
FORCEADD TAP..1
(-6075 2775);
FORCEPROP 3 LASTPIN (-6125 2775) SIG_NAME M_F_CPU0_SB_DQ<5>
J 0
(-6115 2785);
DISPLAY 0.659574 (-6115 2785);
PAINT MONO (-6115 2785);
DISPLAY INVISIBLE (-6115 2785);
FORCEPROP 1 LASTPIN (-6125 2775) BN 5
J 0
(-6137 2783);
DISPLAY 0.489362 (-6137 2783);
PAINT GREEN (-6137 2783);
FORCEPROP 2 LAST CDS_LIB mstr_standard
J 0
(-6075 2775);
DISPLAY 0.723404 (-6075 2775);
PAINT MONO (-6075 2775);
DISPLAY INVISIBLE (-6075 2775);
FORCEPROP 1 LAST BODY_TYPE PLUMBING
J 0
(-6075 2825);
DISPLAY 0.872340 (-6075 2825);
PAINT GREEN (-6075 2825);
DISPLAY INVISIBLE (-6075 2825);
FORCEPROP 1 LAST HDL_TAP TRUE
J 0
(-5750 2650);
DISPLAY 0.872340 (-5750 2650);
DISPLAY INVISIBLE (-5750 2650);
FORCEPROP 1 LAST PATH I277
J 0
(-6077 2775);
DISPLAY 0.872340 (-6077 2775);
PAINT GREEN (-6077 2775);
DISPLAY INVISIBLE (-6077 2775);
FORCEADD TAP..1
(-6075 2725);
FORCEPROP 3 LASTPIN (-6125 2725) SIG_NAME M_F_CPU0_SB_DQ<4>
J 0
(-6115 2735);
DISPLAY 0.659574 (-6115 2735);
PAINT MONO (-6115 2735);
DISPLAY INVISIBLE (-6115 2735);
FORCEPROP 1 LASTPIN (-6125 2725) BN 4
J 0
(-6137 2733);
DISPLAY 0.489362 (-6137 2733);
PAINT GREEN (-6137 2733);
FORCEPROP 2 LAST CDS_LIB mstr_standard
J 0
(-6075 2725);
DISPLAY 0.723404 (-6075 2725);
PAINT MONO (-6075 2725);
DISPLAY INVISIBLE (-6075 2725);
FORCEPROP 1 LAST BODY_TYPE PLUMBING
J 0
(-6075 2775);
DISPLAY 0.872340 (-6075 2775);
PAINT GREEN (-6075 2775);
DISPLAY INVISIBLE (-6075 2775);
FORCEPROP 1 LAST HDL_TAP TRUE
J 0
(-5750 2600);
DISPLAY 0.872340 (-5750 2600);
DISPLAY INVISIBLE (-5750 2600);
FORCEPROP 1 LAST PATH I278
J 0
(-6077 2725);
DISPLAY 0.872340 (-6077 2725);
PAINT GREEN (-6077 2725);
DISPLAY INVISIBLE (-6077 2725);
FORCEADD TAP..1
(-6075 2675);
FORCEPROP 3 LASTPIN (-6125 2675) SIG_NAME M_F_CPU0_SB_DQ<3>
J 0
(-6115 2685);
DISPLAY 0.659574 (-6115 2685);
PAINT MONO (-6115 2685);
DISPLAY INVISIBLE (-6115 2685);
FORCEPROP 1 LASTPIN (-6125 2675) BN 3
J 0
(-6137 2683);
DISPLAY 0.489362 (-6137 2683);
PAINT GREEN (-6137 2683);
FORCEPROP 2 LAST CDS_LIB mstr_standard
J 0
(-6075 2675);
DISPLAY 0.723404 (-6075 2675);
PAINT MONO (-6075 2675);
DISPLAY INVISIBLE (-6075 2675);
FORCEPROP 1 LAST BODY_TYPE PLUMBING
J 0
(-6075 2725);
DISPLAY 0.872340 (-6075 2725);
PAINT GREEN (-6075 2725);
DISPLAY INVISIBLE (-6075 2725);
FORCEPROP 1 LAST HDL_TAP TRUE
J 0
(-5750 2550);
DISPLAY 0.872340 (-5750 2550);
DISPLAY INVISIBLE (-5750 2550);
FORCEPROP 1 LAST PATH I279
J 0
(-6077 2675);
DISPLAY 0.872340 (-6077 2675);
PAINT GREEN (-6077 2675);
DISPLAY INVISIBLE (-6077 2675);
FORCEADD TAP..1
(-6075 2625);
FORCEPROP 3 LASTPIN (-6125 2625) SIG_NAME M_F_CPU0_SB_DQ<2>
J 0
(-6115 2635);
DISPLAY 0.659574 (-6115 2635);
PAINT MONO (-6115 2635);
DISPLAY INVISIBLE (-6115 2635);
FORCEPROP 1 LASTPIN (-6125 2625) BN 2
J 0
(-6137 2633);
DISPLAY 0.489362 (-6137 2633);
PAINT GREEN (-6137 2633);
FORCEPROP 2 LAST CDS_LIB mstr_standard
J 0
(-6075 2625);
DISPLAY 0.723404 (-6075 2625);
PAINT MONO (-6075 2625);
DISPLAY INVISIBLE (-6075 2625);
FORCEPROP 1 LAST BODY_TYPE PLUMBING
J 0
(-6075 2675);
DISPLAY 0.872340 (-6075 2675);
PAINT GREEN (-6075 2675);
DISPLAY INVISIBLE (-6075 2675);
FORCEPROP 1 LAST HDL_TAP TRUE
J 0
(-5750 2500);
DISPLAY 0.872340 (-5750 2500);
DISPLAY INVISIBLE (-5750 2500);
FORCEPROP 1 LAST PATH I280
J 0
(-6077 2625);
DISPLAY 0.872340 (-6077 2625);
PAINT GREEN (-6077 2625);
DISPLAY INVISIBLE (-6077 2625);
FORCEADD TAP..1
(-6075 2525);
FORCEPROP 3 LASTPIN (-6125 2525) SIG_NAME M_F_CPU0_SB_DQ<0>
J 0
(-6115 2535);
DISPLAY 0.659574 (-6115 2535);
PAINT MONO (-6115 2535);
DISPLAY INVISIBLE (-6115 2535);
FORCEPROP 1 LASTPIN (-6125 2525) BN 0
J 0
(-6137 2533);
DISPLAY 0.489362 (-6137 2533);
PAINT GREEN (-6137 2533);
FORCEPROP 2 LAST CDS_LIB mstr_standard
J 0
(-6075 2525);
DISPLAY 0.723404 (-6075 2525);
PAINT MONO (-6075 2525);
DISPLAY INVISIBLE (-6075 2525);
FORCEPROP 1 LAST BODY_TYPE PLUMBING
J 0
(-6075 2575);
DISPLAY 0.872340 (-6075 2575);
PAINT GREEN (-6075 2575);
DISPLAY INVISIBLE (-6075 2575);
FORCEPROP 1 LAST HDL_TAP TRUE
J 0
(-5750 2400);
DISPLAY 0.872340 (-5750 2400);
DISPLAY INVISIBLE (-5750 2400);
FORCEPROP 1 LAST PATH I281
J 0
(-6077 2525);
DISPLAY 0.872340 (-6077 2525);
PAINT GREEN (-6077 2525);
DISPLAY INVISIBLE (-6077 2525);
FORCEADD TAP..1
(-6075 2575);
FORCEPROP 3 LASTPIN (-6125 2575) SIG_NAME M_F_CPU0_SB_DQ<1>
J 0
(-6115 2585);
DISPLAY 0.659574 (-6115 2585);
PAINT MONO (-6115 2585);
DISPLAY INVISIBLE (-6115 2585);
FORCEPROP 1 LASTPIN (-6125 2575) BN 1
J 0
(-6137 2583);
DISPLAY 0.489362 (-6137 2583);
PAINT GREEN (-6137 2583);
FORCEPROP 2 LAST CDS_LIB mstr_standard
J 0
(-6075 2575);
DISPLAY 0.723404 (-6075 2575);
PAINT MONO (-6075 2575);
DISPLAY INVISIBLE (-6075 2575);
FORCEPROP 1 LAST BODY_TYPE PLUMBING
J 0
(-6075 2625);
DISPLAY 0.872340 (-6075 2625);
PAINT GREEN (-6075 2625);
DISPLAY INVISIBLE (-6075 2625);
FORCEPROP 1 LAST HDL_TAP TRUE
J 0
(-5750 2450);
DISPLAY 0.872340 (-5750 2450);
DISPLAY INVISIBLE (-5750 2450);
FORCEPROP 1 LAST PATH I282
J 0
(-6077 2575);
DISPLAY 0.872340 (-6077 2575);
PAINT GREEN (-6077 2575);
DISPLAY INVISIBLE (-6077 2575);
FORCEADD OFFPAGE..3
(-5450 4100);
FORCEPROP 2 LAST $XR0 15 
J 0
(-5236 4100);
DISPLAY 0.638298 (-5236 4100);
PAINT MONO (-5236 4100);
FORCEPROP 2 LAST CDS_LIB mstr_standard
J 0
(-5450 4100);
DISPLAY 0.723404 (-5450 4100);
PAINT MONO (-5450 4100);
DISPLAY INVISIBLE (-5450 4100);
FORCEPROP 1 LAST OFFPAGE TRUE
J 0
(-5125 3975);
DISPLAY 0.872340 (-5125 3975);
PAINT GREEN (-5125 3975);
DISPLAY INVISIBLE (-5125 3975);
FORCEPROP 1 LAST COMMENT_BODY TRUE
J 0
(-5500 4000);
DISPLAY 0.872340 (-5500 4000);
PAINT GREEN (-5500 4000);
DISPLAY INVISIBLE (-5500 4000);
FORCEPROP 2 LAST PATH I283
J 0
(-5125 4150);
DISPLAY 0.808511 (-5125 4150);
DISPLAY INVISIBLE (-5125 4150);
FORCEADD OFFPAGE..3
(-5450 5750);
FORCEPROP 2 LAST $XR0 15 
J 0
(-5236 5750);
DISPLAY 0.638298 (-5236 5750);
PAINT MONO (-5236 5750);
FORCEPROP 2 LAST CDS_LIB mstr_standard
J 0
(-5450 5750);
DISPLAY 0.723404 (-5450 5750);
PAINT MONO (-5450 5750);
DISPLAY INVISIBLE (-5450 5750);
FORCEPROP 1 LAST OFFPAGE TRUE
J 0
(-5125 5625);
DISPLAY 0.872340 (-5125 5625);
PAINT GREEN (-5125 5625);
DISPLAY INVISIBLE (-5125 5625);
FORCEPROP 1 LAST COMMENT_BODY TRUE
J 0
(-5500 5650);
DISPLAY 0.872340 (-5500 5650);
PAINT GREEN (-5500 5650);
DISPLAY INVISIBLE (-5500 5650);
FORCEPROP 2 LAST PATH I284
J 0
(-5225 5800);
DISPLAY 0.808511 (-5225 5800);
DISPLAY INVISIBLE (-5225 5800);
FORCEADD GND..1
(-6400 1375);
FORCEPROP 3 LASTPIN (-6400 1425) SIG_NAME GND\g
J 0
(-6390 1435);
DISPLAY 0.659574 (-6390 1435);
PAINT MONO (-6390 1435);
DISPLAY INVISIBLE (-6390 1435);
FORCEPROP 1 LAST VOLTAGE 0.0
J 0
(-6445 1332);
DISPLAY 0.723404 (-6445 1332);
PAINT SKYBLUE (-6445 1332);
DISPLAY INVISIBLE (-6445 1332);
FORCEPROP 2 LAST BOM_COST MEM
J 0
(-6500 1450);
DISPLAY 0.808511 (-6500 1450);
DISPLAY INVISIBLE (-6500 1450);
FORCEPROP 2 LAST CDS_LIB mstr_symbols
J 0
(-6400 1375);
DISPLAY 0.808511 (-6400 1375);
DISPLAY INVISIBLE (-6400 1375);
FORCEPROP 1 LAST SIZE 1B
J 0
(-6325 1325);
DISPLAY 0.851064 (-6325 1325);
PAINT GREEN (-6325 1325);
DISPLAY INVISIBLE (-6325 1325);
FORCEPROP 1 LAST BODY_TYPE PLUMBING
J 0
(-6445 1332);
DISPLAY 0.340426 (-6445 1332);
PAINT GREEN (-6445 1332);
DISPLAY INVISIBLE (-6445 1332);
FORCEPROP 1 LAST HDL_POWER GND
J 0
(-6400 1525);
DISPLAY 0.851064 (-6400 1525);
PAINT GREEN (-6400 1525);
DISPLAY INVISIBLE (-6400 1525);
FORCEPROP 1 LAST PATH I332
J 0
(-6325 1375);
DISPLAY 0.872340 (-6325 1375);
PAINT GREEN (-6325 1375);
DISPLAY INVISIBLE (-6325 1375);
FORCEADD OFFPAGE..5
(-7175 1775);
FORCEPROP 2 LAST $XR0 91 
J 0
(-7429 1775);
DISPLAY 0.638298 (-7429 1775);
PAINT MONO (-7429 1775);
FORCEPROP 2 LAST BOM_COST MEM
J 0
(-7250 1850);
DISPLAY 0.808511 (-7250 1850);
DISPLAY INVISIBLE (-7250 1850);
FORCEPROP 2 LAST CDS_LIB mstr_standard
J 0
(-7175 1775);
DISPLAY 0.808511 (-7175 1775);
DISPLAY INVISIBLE (-7175 1775);
FORCEPROP 1 LAST OFFPAGE TRUE
J 0
(-6850 1650);
DISPLAY 0.872340 (-6850 1650);
PAINT GREEN (-6850 1650);
DISPLAY INVISIBLE (-6850 1650);
FORCEPROP 1 LAST COMMENT_BODY TRUE
J 0
(-7075 1700);
DISPLAY 0.872340 (-7075 1700);
PAINT GREEN (-7075 1700);
DISPLAY INVISIBLE (-7075 1700);
FORCEPROP 2 LAST PATH I333
J 0
(-7125 1850);
DISPLAY 0.808511 (-7125 1850);
DISPLAY INVISIBLE (-7125 1850);
FORCEADD OFFPAGE..1
(-8375 3225);
FORCEPROP 2 LAST $XR0 91 
J 0
(-8626 3225);
DISPLAY 0.638298 (-8626 3225);
PAINT MONO (-8626 3225);
FORCEPROP 2 LAST CDS_LIB mstr_standard
J 0
(-8375 3225);
DISPLAY 0.808511 (-8375 3225);
DISPLAY INVISIBLE (-8375 3225);
FORCEPROP 1 LAST OFFPAGE TRUE
J 0
(-8050 3100);
DISPLAY 0.872340 (-8050 3100);
PAINT GREEN (-8050 3100);
DISPLAY INVISIBLE (-8050 3100);
FORCEPROP 1 LAST COMMENT_BODY TRUE
J 0
(-8250 3125);
DISPLAY 0.872340 (-8250 3125);
PAINT GREEN (-8250 3125);
DISPLAY INVISIBLE (-8250 3125);
FORCEPROP 2 LAST PATH I334
J 0
(-8325 3300);
DISPLAY 0.808511 (-8325 3300);
DISPLAY INVISIBLE (-8325 3300);
FORCEADD Q_RES..2
(-6400 1600);
FORCEPROP 1 LAST LOCATION R764
J 0
(-6355 1725);
DISPLAY 0.489362 (-6355 1725);
PAINT SKYBLUE (-6355 1725);
FORCEPROP 0 LAST $SEC 1
J 0
(-6350 1775);
DISPLAY 0.680851 (-6350 1775);
PAINT MONO (-6350 1775);
DISPLAY INVISIBLE (-6350 1775);
FORCEPROP 0 LAST CDS_SEC 1
J 0
(-6350 1775);
DISPLAY 1.021277 (-6350 1775);
DISPLAY INVISIBLE (-6350 1775);
FORCEPROP 1 LASTPIN (-6400 1700) $PN 1
J 0
(-6395 1662);
DISPLAY 0.489362 (-6395 1662);
PAINT MONO (-6395 1662);
FORCEPROP 1 LASTPIN (-6400 1500) $PN 2
J 0
(-6395 1510);
DISPLAY 0.489362 (-6395 1510);
PAINT MONO (-6395 1510);
FORCEPROP 1 LAST PACK_TYPE 0402LF
J 0
(-6360 1425);
DISPLAY 0.489362 (-6360 1425);
PAINT SKYBLUE (-6360 1425);
FORCEPROP 1 LAST VALUE 84.5K
J 0
(-6355 1675);
DISPLAY 0.489362 (-6355 1675);
PAINT SKYBLUE (-6355 1675);
FORCEPROP 1 LAST TOLERANCE 1%
J 0
(-6355 1625);
DISPLAY 0.489362 (-6355 1625);
PAINT SKYBLUE (-6355 1625);
FORCEPROP 1 LAST MATERIAL CHIP
J 0
(-6360 1525);
DISPLAY 0.489362 (-6360 1525);
PAINT SKYBLUE (-6360 1525);
FORCEPROP 1 LAST WATTAGE 1/16W
J 0
(-6360 1575);
DISPLAY 0.489362 (-6360 1575);
PAINT SKYBLUE (-6360 1575);
FORCEPROP 2 LAST CDS_LIB pure_quanta
J 0
(-6400 1600);
DISPLAY INVISIBLE (-6400 1600);
FORCEPROP 1 LAST PATH I349
J 0
(-6350 1775);
DISPLAY 0.978723 (-6350 1775);
PAINT WHITE (-6350 1775);
DISPLAY INVISIBLE (-6350 1775);
FORCEPROP 1 LAST PART_NUMBER CS38452FB05
J 0
(-6360 1475);
DISPLAY 0.489362 (-6360 1475);
PAINT SKYBLUE (-6360 1475);
DISPLAY INVISIBLE (-6360 1475);
FORCEADD SCONN288_DDR506112002KQ..1
(-6925 3975);
FORCEPROP 1 LAST LOCATION J23
J 0
(-7375 6050);
DISPLAY 0.468085 (-7375 6050);
PAINT SKYBLUE (-7375 6050);
FORCEPROP 0 LAST $SEC 1
J 0
(-7375 6200);
DISPLAY 0.680851 (-7375 6200);
PAINT MONO (-7375 6200);
DISPLAY INVISIBLE (-7375 6200);
FORCEPROP 2 LAST CDS_SEC 1
J 0
(-7375 6200);
DISPLAY 1.021277 (-7375 6200);
DISPLAY INVISIBLE (-7375 6200);
FORCEPROP 0 LASTPIN (-7525 3375) $PN 62
J 2
(-7535 3385);
DISPLAY 0.680851 (-7535 3385);
PAINT MONO (-7535 3385);
FORCEPROP 0 LASTPIN (-7525 5425) $PN 66
J 2
(-7535 5435);
DISPLAY 0.680851 (-7535 5435);
PAINT MONO (-7535 5435);
FORCEPROP 0 LASTPIN (-7525 5025) $PN 76
J 2
(-7535 5035);
DISPLAY 0.680851 (-7535 5035);
PAINT MONO (-7535 5035);
FORCEPROP 0 LASTPIN (-7525 5475) $PN 211
J 2
(-7535 5485);
DISPLAY 0.680851 (-7535 5485);
PAINT MONO (-7535 5485);
FORCEPROP 0 LASTPIN (-7525 5075) $PN 221
J 2
(-7535 5085);
DISPLAY 0.680851 (-7535 5085);
PAINT MONO (-7535 5085);
FORCEPROP 0 LASTPIN (-7525 5525) $PN 68
J 2
(-7535 5535);
DISPLAY 0.680851 (-7535 5535);
PAINT MONO (-7535 5535);
FORCEPROP 0 LASTPIN (-7525 5125) $PN 78
J 2
(-7535 5135);
DISPLAY 0.680851 (-7535 5135);
PAINT MONO (-7535 5135);
FORCEPROP 0 LASTPIN (-7525 5575) $PN 213
J 2
(-7535 5585);
DISPLAY 0.680851 (-7535 5585);
PAINT MONO (-7535 5585);
FORCEPROP 0 LASTPIN (-7525 5175) $PN 223
J 2
(-7535 5185);
DISPLAY 0.680851 (-7535 5185);
PAINT MONO (-7535 5185);
FORCEPROP 0 LASTPIN (-7525 5625) $PN 70
J 2
(-7535 5635);
DISPLAY 0.680851 (-7535 5635);
PAINT MONO (-7535 5635);
FORCEPROP 0 LASTPIN (-7525 5225) $PN 80
J 2
(-7535 5235);
DISPLAY 0.680851 (-7535 5235);
PAINT MONO (-7535 5235);
FORCEPROP 0 LASTPIN (-7525 5675) $PN 215
J 2
(-7535 5685);
DISPLAY 0.680851 (-7535 5685);
PAINT MONO (-7535 5685);
FORCEPROP 0 LASTPIN (-7525 5275) $PN 225
J 2
(-7535 5285);
DISPLAY 0.680851 (-7535 5285);
PAINT MONO (-7535 5285);
FORCEPROP 0 LASTPIN (-7525 5725) $PN 72
J 2
(-7535 5735);
DISPLAY 0.680851 (-7535 5735);
PAINT MONO (-7535 5735);
FORCEPROP 0 LASTPIN (-7525 5325) $PN 82
J 2
(-7535 5335);
DISPLAY 0.680851 (-7535 5335);
PAINT MONO (-7535 5335);
FORCEPROP 0 LASTPIN (-7525 3975) $PN 51
J 2
(-7535 3985);
DISPLAY 0.680851 (-7535 3985);
PAINT MONO (-7535 3985);
FORCEPROP 0 LASTPIN (-7525 3525) $PN 96
J 2
(-7535 3535);
DISPLAY 0.680851 (-7535 3535);
PAINT MONO (-7535 3535);
FORCEPROP 0 LASTPIN (-7525 4025) $PN 53
J 2
(-7535 4035);
DISPLAY 0.680851 (-7535 4035);
PAINT MONO (-7535 4035);
FORCEPROP 0 LASTPIN (-7525 3575) $PN 98
J 2
(-7535 3585);
DISPLAY 0.680851 (-7535 3585);
PAINT MONO (-7535 3585);
FORCEPROP 0 LASTPIN (-7525 4075) $PN 196
J 2
(-7535 4085);
DISPLAY 0.680851 (-7535 4085);
PAINT MONO (-7535 4085);
FORCEPROP 0 LASTPIN (-7525 3625) $PN 241
J 2
(-7535 3635);
DISPLAY 0.680851 (-7535 3635);
PAINT MONO (-7535 3635);
FORCEPROP 0 LASTPIN (-7525 4125) $PN 198
J 2
(-7535 4135);
DISPLAY 0.680851 (-7535 4135);
PAINT MONO (-7535 4135);
FORCEPROP 0 LASTPIN (-7525 3675) $PN 243
J 2
(-7535 3685);
DISPLAY 0.680851 (-7535 3685);
PAINT MONO (-7535 3685);
FORCEPROP 0 LASTPIN (-7525 4175) $PN 58
J 2
(-7535 4185);
DISPLAY 0.680851 (-7535 4185);
PAINT MONO (-7535 4185);
FORCEPROP 0 LASTPIN (-7525 3725) $PN 89
J 2
(-7535 3735);
DISPLAY 0.680851 (-7535 3735);
PAINT MONO (-7535 3735);
FORCEPROP 0 LASTPIN (-7525 4225) $PN 60
J 2
(-7535 4235);
DISPLAY 0.680851 (-7535 4235);
PAINT MONO (-7535 4235);
FORCEPROP 0 LASTPIN (-7525 3775) $PN 91
J 2
(-7535 3785);
DISPLAY 0.680851 (-7535 3785);
PAINT MONO (-7535 3785);
FORCEPROP 0 LASTPIN (-7525 4275) $PN 203
J 2
(-7535 4285);
DISPLAY 0.680851 (-7535 4285);
PAINT MONO (-7535 4285);
FORCEPROP 0 LASTPIN (-7525 3825) $PN 234
J 2
(-7535 3835);
DISPLAY 0.680851 (-7535 3835);
PAINT MONO (-7535 3835);
FORCEPROP 0 LASTPIN (-7525 4325) $PN 205
J 2
(-7535 4335);
DISPLAY 0.680851 (-7535 4335);
PAINT MONO (-7535 4335);
FORCEPROP 0 LASTPIN (-7525 3875) $PN 236
J 2
(-7535 3885);
DISPLAY 0.680851 (-7535 3885);
PAINT MONO (-7535 3885);
FORCEPROP 0 LASTPIN (-7525 4425) $PN 218
J 2
(-7535 4435);
DISPLAY 0.680851 (-7535 4435);
PAINT MONO (-7535 4435);
FORCEPROP 0 LASTPIN (-7525 4475) $PN 217
J 2
(-7535 4485);
DISPLAY 0.680851 (-7535 4485);
PAINT MONO (-7535 4485);
FORCEPROP 0 LASTPIN (-7525 4725) $PN 64
J 2
(-7535 4735);
DISPLAY 0.680851 (-7535 4735);
PAINT MONO (-7535 4735);
FORCEPROP 0 LASTPIN (-7525 4575) $PN 84
J 2
(-7535 4585);
DISPLAY 0.680851 (-7535 4585);
PAINT MONO (-7535 4585);
FORCEPROP 0 LASTPIN (-7525 4775) $PN 209
J 2
(-7535 4785);
DISPLAY 0.680851 (-7535 4785);
PAINT MONO (-7535 4785);
FORCEPROP 0 LASTPIN (-7525 4625) $PN 229
J 2
(-7535 4635);
DISPLAY 0.680851 (-7535 4635);
PAINT MONO (-7535 4635);
FORCEPROP 0 LASTPIN (-6325 4175) $PN 7
J 0
(-6315 4185);
DISPLAY 0.680851 (-6315 4185);
PAINT MONO (-6315 4185);
FORCEPROP 0 LASTPIN (-6325 2525) $PN 100
J 0
(-6315 2535);
DISPLAY 0.680851 (-6315 2535);
PAINT MONO (-6315 2535);
FORCEPROP 0 LASTPIN (-6325 4225) $PN 9
J 0
(-6315 4235);
DISPLAY 0.680851 (-6315 4235);
PAINT MONO (-6315 4235);
FORCEPROP 0 LASTPIN (-6325 2575) $PN 102
J 0
(-6315 2585);
DISPLAY 0.680851 (-6315 2585);
PAINT MONO (-6315 2585);
FORCEPROP 0 LASTPIN (-6325 4275) $PN 152
J 0
(-6315 4285);
DISPLAY 0.680851 (-6315 4285);
PAINT MONO (-6315 4285);
FORCEPROP 0 LASTPIN (-6325 2625) $PN 245
J 0
(-6315 2635);
DISPLAY 0.680851 (-6315 2635);
PAINT MONO (-6315 2635);
FORCEPROP 0 LASTPIN (-6325 4325) $PN 154
J 0
(-6315 4335);
DISPLAY 0.680851 (-6315 4335);
PAINT MONO (-6315 4335);
FORCEPROP 0 LASTPIN (-6325 2675) $PN 247
J 0
(-6315 2685);
DISPLAY 0.680851 (-6315 2685);
PAINT MONO (-6315 2685);
FORCEPROP 0 LASTPIN (-6325 4375) $PN 14
J 0
(-6315 4385);
DISPLAY 0.680851 (-6315 4385);
PAINT MONO (-6315 4385);
FORCEPROP 0 LASTPIN (-6325 2725) $PN 107
J 0
(-6315 2735);
DISPLAY 0.680851 (-6315 2735);
PAINT MONO (-6315 2735);
FORCEPROP 0 LASTPIN (-6325 4425) $PN 16
J 0
(-6315 4435);
DISPLAY 0.680851 (-6315 4435);
PAINT MONO (-6315 4435);
FORCEPROP 0 LASTPIN (-6325 2775) $PN 109
J 0
(-6315 2785);
DISPLAY 0.680851 (-6315 2785);
PAINT MONO (-6315 2785);
FORCEPROP 0 LASTPIN (-6325 4475) $PN 159
J 0
(-6315 4485);
DISPLAY 0.680851 (-6315 4485);
PAINT MONO (-6315 4485);
FORCEPROP 0 LASTPIN (-6325 2825) $PN 252
J 0
(-6315 2835);
DISPLAY 0.680851 (-6315 2835);
PAINT MONO (-6315 2835);
FORCEPROP 0 LASTPIN (-6325 4525) $PN 161
J 0
(-6315 4535);
DISPLAY 0.680851 (-6315 4535);
PAINT MONO (-6315 4535);
FORCEPROP 0 LASTPIN (-6325 2875) $PN 254
J 0
(-6315 2885);
DISPLAY 0.680851 (-6315 2885);
PAINT MONO (-6315 2885);
FORCEPROP 0 LASTPIN (-6325 4575) $PN 18
J 0
(-6315 4585);
DISPLAY 0.680851 (-6315 4585);
PAINT MONO (-6315 4585);
FORCEPROP 0 LASTPIN (-6325 2925) $PN 111
J 0
(-6315 2935);
DISPLAY 0.680851 (-6315 2935);
PAINT MONO (-6315 2935);
FORCEPROP 0 LASTPIN (-6325 4625) $PN 20
J 0
(-6315 4635);
DISPLAY 0.680851 (-6315 4635);
PAINT MONO (-6315 4635);
FORCEPROP 0 LASTPIN (-6325 2975) $PN 113
J 0
(-6315 2985);
DISPLAY 0.680851 (-6315 2985);
PAINT MONO (-6315 2985);
FORCEPROP 0 LASTPIN (-6325 4675) $PN 163
J 0
(-6315 4685);
DISPLAY 0.680851 (-6315 4685);
PAINT MONO (-6315 4685);
FORCEPROP 0 LASTPIN (-6325 3025) $PN 256
J 0
(-6315 3035);
DISPLAY 0.680851 (-6315 3035);
PAINT MONO (-6315 3035);
FORCEPROP 0 LASTPIN (-6325 4725) $PN 165
J 0
(-6315 4735);
DISPLAY 0.680851 (-6315 4735);
PAINT MONO (-6315 4735);
FORCEPROP 0 LASTPIN (-6325 3075) $PN 258
J 0
(-6315 3085);
DISPLAY 0.680851 (-6315 3085);
PAINT MONO (-6315 3085);
FORCEPROP 0 LASTPIN (-6325 4775) $PN 25
J 0
(-6315 4785);
DISPLAY 0.680851 (-6315 4785);
PAINT MONO (-6315 4785);
FORCEPROP 0 LASTPIN (-6325 3125) $PN 118
J 0
(-6315 3135);
DISPLAY 0.680851 (-6315 3135);
PAINT MONO (-6315 3135);
FORCEPROP 0 LASTPIN (-6325 4825) $PN 27
J 0
(-6315 4835);
DISPLAY 0.680851 (-6315 4835);
PAINT MONO (-6315 4835);
FORCEPROP 0 LASTPIN (-6325 3175) $PN 120
J 0
(-6315 3185);
DISPLAY 0.680851 (-6315 3185);
PAINT MONO (-6315 3185);
FORCEPROP 0 LASTPIN (-6325 4875) $PN 170
J 0
(-6315 4885);
DISPLAY 0.680851 (-6315 4885);
PAINT MONO (-6315 4885);
FORCEPROP 0 LASTPIN (-6325 3225) $PN 263
J 0
(-6315 3235);
DISPLAY 0.680851 (-6315 3235);
PAINT MONO (-6315 3235);
FORCEPROP 0 LASTPIN (-6325 4925) $PN 172
J 0
(-6315 4935);
DISPLAY 0.680851 (-6315 4935);
PAINT MONO (-6315 4935);
FORCEPROP 0 LASTPIN (-6325 3275) $PN 265
J 0
(-6315 3285);
DISPLAY 0.680851 (-6315 3285);
PAINT MONO (-6315 3285);
FORCEPROP 0 LASTPIN (-6325 4975) $PN 29
J 0
(-6315 4985);
DISPLAY 0.680851 (-6315 4985);
PAINT MONO (-6315 4985);
FORCEPROP 0 LASTPIN (-6325 3325) $PN 122
J 0
(-6315 3335);
DISPLAY 0.680851 (-6315 3335);
PAINT MONO (-6315 3335);
FORCEPROP 0 LASTPIN (-6325 5025) $PN 31
J 0
(-6315 5035);
DISPLAY 0.680851 (-6315 5035);
PAINT MONO (-6315 5035);
FORCEPROP 0 LASTPIN (-6325 3375) $PN 124
J 0
(-6315 3385);
DISPLAY 0.680851 (-6315 3385);
PAINT MONO (-6315 3385);
FORCEPROP 0 LASTPIN (-6325 5075) $PN 174
J 0
(-6315 5085);
DISPLAY 0.680851 (-6315 5085);
PAINT MONO (-6315 5085);
FORCEPROP 0 LASTPIN (-6325 3425) $PN 267
J 0
(-6315 3435);
DISPLAY 0.680851 (-6315 3435);
PAINT MONO (-6315 3435);
FORCEPROP 0 LASTPIN (-6325 5125) $PN 176
J 0
(-6315 5135);
DISPLAY 0.680851 (-6315 5135);
PAINT MONO (-6315 5135);
FORCEPROP 0 LASTPIN (-6325 3475) $PN 269
J 0
(-6315 3485);
DISPLAY 0.680851 (-6315 3485);
PAINT MONO (-6315 3485);
FORCEPROP 0 LASTPIN (-6325 5175) $PN 36
J 0
(-6315 5185);
DISPLAY 0.680851 (-6315 5185);
PAINT MONO (-6315 5185);
FORCEPROP 0 LASTPIN (-6325 3525) $PN 129
J 0
(-6315 3535);
DISPLAY 0.680851 (-6315 3535);
PAINT MONO (-6315 3535);
FORCEPROP 0 LASTPIN (-6325 5225) $PN 38
J 0
(-6315 5235);
DISPLAY 0.680851 (-6315 5235);
PAINT MONO (-6315 5235);
FORCEPROP 0 LASTPIN (-6325 3575) $PN 131
J 0
(-6315 3585);
DISPLAY 0.680851 (-6315 3585);
PAINT MONO (-6315 3585);
FORCEPROP 0 LASTPIN (-6325 5275) $PN 181
J 0
(-6315 5285);
DISPLAY 0.680851 (-6315 5285);
PAINT MONO (-6315 5285);
FORCEPROP 0 LASTPIN (-6325 3625) $PN 274
J 0
(-6315 3635);
DISPLAY 0.680851 (-6315 3635);
PAINT MONO (-6315 3635);
FORCEPROP 0 LASTPIN (-6325 5325) $PN 183
J 0
(-6315 5335);
DISPLAY 0.680851 (-6315 5335);
PAINT MONO (-6315 5335);
FORCEPROP 0 LASTPIN (-6325 3675) $PN 276
J 0
(-6315 3685);
DISPLAY 0.680851 (-6315 3685);
PAINT MONO (-6315 3685);
FORCEPROP 0 LASTPIN (-6325 5375) $PN 40
J 0
(-6315 5385);
DISPLAY 0.680851 (-6315 5385);
PAINT MONO (-6315 5385);
FORCEPROP 0 LASTPIN (-6325 3725) $PN 133
J 0
(-6315 3735);
DISPLAY 0.680851 (-6315 3735);
PAINT MONO (-6315 3735);
FORCEPROP 0 LASTPIN (-6325 5425) $PN 42
J 0
(-6315 5435);
DISPLAY 0.680851 (-6315 5435);
PAINT MONO (-6315 5435);
FORCEPROP 0 LASTPIN (-6325 3775) $PN 135
J 0
(-6315 3785);
DISPLAY 0.680851 (-6315 3785);
PAINT MONO (-6315 3785);
FORCEPROP 0 LASTPIN (-6325 5475) $PN 185
J 0
(-6315 5485);
DISPLAY 0.680851 (-6315 5485);
PAINT MONO (-6315 5485);
FORCEPROP 0 LASTPIN (-6325 3825) $PN 278
J 0
(-6315 3835);
DISPLAY 0.680851 (-6315 3835);
PAINT MONO (-6315 3835);
FORCEPROP 0 LASTPIN (-6325 5525) $PN 187
J 0
(-6315 5535);
DISPLAY 0.680851 (-6315 5535);
PAINT MONO (-6315 5535);
FORCEPROP 0 LASTPIN (-6325 3875) $PN 280
J 0
(-6315 3885);
DISPLAY 0.680851 (-6315 3885);
PAINT MONO (-6315 3885);
FORCEPROP 0 LASTPIN (-6325 5575) $PN 47
J 0
(-6315 5585);
DISPLAY 0.680851 (-6315 5585);
PAINT MONO (-6315 5585);
FORCEPROP 0 LASTPIN (-6325 3925) $PN 140
J 0
(-6315 3935);
DISPLAY 0.680851 (-6315 3935);
PAINT MONO (-6315 3935);
FORCEPROP 0 LASTPIN (-6325 5625) $PN 49
J 0
(-6315 5635);
DISPLAY 0.680851 (-6315 5635);
PAINT MONO (-6315 5635);
FORCEPROP 0 LASTPIN (-6325 3975) $PN 142
J 0
(-6315 3985);
DISPLAY 0.680851 (-6315 3985);
PAINT MONO (-6315 3985);
FORCEPROP 0 LASTPIN (-6325 5675) $PN 192
J 0
(-6315 5685);
DISPLAY 0.680851 (-6315 5685);
PAINT MONO (-6315 5685);
FORCEPROP 0 LASTPIN (-6325 4025) $PN 285
J 0
(-6315 4035);
DISPLAY 0.680851 (-6315 4035);
PAINT MONO (-6315 4035);
FORCEPROP 0 LASTPIN (-6325 5725) $PN 194
J 0
(-6315 5735);
DISPLAY 0.680851 (-6315 5735);
PAINT MONO (-6315 5735);
FORCEPROP 0 LASTPIN (-6325 4075) $PN 287
J 0
(-6315 4085);
DISPLAY 0.680851 (-6315 4085);
PAINT MONO (-6315 4085);
FORCEPROP 0 LASTPIN (-7525 3225) $PN 148
J 2
(-7535 3235);
DISPLAY 0.680851 (-7535 3235);
PAINT MONO (-7535 3235);
FORCEPROP 0 LASTPIN (-7525 3125) $PN 4
J 2
(-7535 3135);
DISPLAY 0.680851 (-7535 3135);
PAINT MONO (-7535 3135);
FORCEPROP 0 LASTPIN (-7525 3175) $PN 5
J 2
(-7535 3185);
DISPLAY 0.680851 (-7535 3185);
PAINT MONO (-7535 3185);
FORCEPROP 0 LASTPIN (-7525 2325) $PN 86
J 2
(-7535 2335);
DISPLAY 0.680851 (-7535 2335);
PAINT MONO (-7535 2335);
FORCEPROP 0 LASTPIN (-7525 2275) $PN 87
J 2
(-7535 2285);
DISPLAY 0.680851 (-7535 2285);
PAINT MONO (-7535 2285);
FORCEPROP 0 LASTPIN (-7525 4925) $PN 74
J 2
(-7535 4935);
DISPLAY 0.680851 (-7535 4935);
PAINT MONO (-7535 4935);
FORCEPROP 0 LASTPIN (-7525 4875) $PN 227
J 2
(-7535 4885);
DISPLAY 0.680851 (-7535 4885);
PAINT MONO (-7535 4885);
FORCEPROP 0 LASTPIN (-7525 2875) $PN 147
J 2
(-7535 2885);
DISPLAY 0.680851 (-7535 2885);
PAINT MONO (-7535 2885);
FORCEPROP 0 LASTPIN (-7525 3425) $PN 207
J 2
(-7535 3435);
DISPLAY 0.680851 (-7535 3435);
PAINT MONO (-7535 3435);
FORCEPROP 0 LASTPIN (-7525 2475) $PN 2
J 2
(-7535 2485);
DISPLAY 0.680851 (-7535 2485);
PAINT MONO (-7535 2485);
FORCEPROP 0 LASTPIN (-7525 2525) $PN 144
J 2
(-7535 2535);
DISPLAY 0.680851 (-7535 2535);
PAINT MONO (-7535 2535);
FORCEPROP 0 LASTPIN (-7525 2575) $PN 149
J 2
(-7535 2585);
DISPLAY 0.680851 (-7535 2585);
PAINT MONO (-7535 2585);
FORCEPROP 0 LASTPIN (-7525 2625) $PN 150
J 2
(-7535 2635);
DISPLAY 0.680851 (-7535 2635);
PAINT MONO (-7535 2635);
FORCEPROP 0 LASTPIN (-7525 2675) $PN 220
J 2
(-7535 2685);
DISPLAY 0.680851 (-7535 2685);
PAINT MONO (-7535 2685);
FORCEPROP 0 LASTPIN (-7525 2725) $PN 231
J 2
(-7535 2735);
DISPLAY 0.680851 (-7535 2735);
PAINT MONO (-7535 2735);
FORCEPROP 0 LASTPIN (-7525 2775) $PN 232
J 2
(-7535 2785);
DISPLAY 0.680851 (-7535 2785);
PAINT MONO (-7535 2785);
FORCEPROP 0 LASTPIN (-7525 3275) $PN 3
J 2
(-7535 3285);
DISPLAY 0.680851 (-7535 3285);
PAINT MONO (-7535 3285);
FORCEPROP 1 LAST MATERIAL IO
J 0
(-7375 5900);
DISPLAY 0.468085 (-7375 5900);
PAINT SKYBLUE (-7375 5900);
FORCEPROP 2 LAST PART_TYPE SMLF
J 0
(-7375 6150);
DISPLAY 1.021277 (-7375 6150);
FORCEPROP 2 LAST VALUE SCONN288_DDR506112002KQ
J 0
(-7375 6100);
DISPLAY 0.489362 (-7375 6100);
PAINT SKYBLUE (-7375 6100);
FORCEPROP 2 LAST CDS_LIB pure_quanta
J 0
(-6925 3975);
DISPLAY INVISIBLE (-6925 3975);
FORCEPROP 1 LAST NEEDS_NO_SIZE TRUE
J 0
(-6925 3975);
DISPLAY 0.723404 (-6925 3975);
PAINT GREEN (-6925 3975);
DISPLAY INVISIBLE (-6925 3975);
FORCEPROP 1 LAST CDS_LMAN_SYM_OUTLINE -450,1900,450,-1850
J 0
(-6925 3975);
DISPLAY 0.468085 (-6925 3975);
PAINT GREEN (-6925 3975);
DISPLAY INVISIBLE (-6925 3975);
FORCEPROP 1 LAST PATH I350
J 0
(-6925 3975);
DISPLAY 0.723404 (-6925 3975);
PAINT GREEN (-6925 3975);
DISPLAY INVISIBLE (-6925 3975);
FORCEPROP 1 LAST PART_NUMBER DFHST8FS479
J 0
(-7375 5975);
DISPLAY 0.468085 (-7375 5975);
PAINT SKYBLUE (-7375 5975);
DISPLAY INVISIBLE (-7375 5975);
FORCEADD SCONN288_DDR506112002KQ..3
(-1325 3950);
FORCEPROP 1 LAST LOCATION J23
J 0
(-1775 5925);
DISPLAY 0.468085 (-1775 5925);
PAINT SKYBLUE (-1775 5925);
FORCEPROP 0 LAST $SEC 3
J 0
(-1775 6075);
DISPLAY 0.680851 (-1775 6075);
PAINT MONO (-1775 6075);
DISPLAY INVISIBLE (-1775 6075);
FORCEPROP 2 LAST CDS_SEC 3
J 0
(-1775 6075);
DISPLAY 1.021277 (-1775 6075);
DISPLAY INVISIBLE (-1775 6075);
FORCEPROP 0 LASTPIN (-725 2350) $PN G1
J 0
(-715 2360);
DISPLAY 0.680851 (-715 2360);
PAINT MONO (-715 2360);
FORCEPROP 0 LASTPIN (-725 2300) $PN G2
J 0
(-715 2310);
DISPLAY 0.680851 (-715 2310);
PAINT MONO (-715 2310);
FORCEPROP 0 LASTPIN (-725 2250) $PN G3
J 0
(-715 2260);
DISPLAY 0.680851 (-715 2260);
PAINT MONO (-715 2260);
FORCEPROP 0 LASTPIN (-1925 5500) $PN 1
J 2
(-1935 5510);
DISPLAY 0.680851 (-1935 5510);
PAINT MONO (-1935 5510);
FORCEPROP 0 LASTPIN (-1925 5550) $PN 145
J 2
(-1935 5560);
DISPLAY 0.680851 (-1935 5560);
PAINT MONO (-1935 5560);
FORCEPROP 0 LASTPIN (-1925 5600) $PN 146
J 2
(-1935 5610);
DISPLAY 0.680851 (-1935 5610);
PAINT MONO (-1935 5610);
FORCEPROP 0 LASTPIN (-725 2450) $PN 6
J 0
(-715 2460);
DISPLAY 0.680851 (-715 2460);
PAINT MONO (-715 2460);
FORCEPROP 0 LASTPIN (-725 2500) $PN 8
J 0
(-715 2510);
DISPLAY 0.680851 (-715 2510);
PAINT MONO (-715 2510);
FORCEPROP 0 LASTPIN (-725 2550) $PN 10
J 0
(-715 2560);
DISPLAY 0.680851 (-715 2560);
PAINT MONO (-715 2560);
FORCEPROP 0 LASTPIN (-725 2600) $PN 13
J 0
(-715 2610);
DISPLAY 0.680851 (-715 2610);
PAINT MONO (-715 2610);
FORCEPROP 0 LASTPIN (-725 2650) $PN 15
J 0
(-715 2660);
DISPLAY 0.680851 (-715 2660);
PAINT MONO (-715 2660);
FORCEPROP 0 LASTPIN (-725 2700) $PN 17
J 0
(-715 2710);
DISPLAY 0.680851 (-715 2710);
PAINT MONO (-715 2710);
FORCEPROP 0 LASTPIN (-725 2750) $PN 19
J 0
(-715 2760);
DISPLAY 0.680851 (-715 2760);
PAINT MONO (-715 2760);
FORCEPROP 0 LASTPIN (-725 2800) $PN 21
J 0
(-715 2810);
DISPLAY 0.680851 (-715 2810);
PAINT MONO (-715 2810);
FORCEPROP 0 LASTPIN (-725 2850) $PN 24
J 0
(-715 2860);
DISPLAY 0.680851 (-715 2860);
PAINT MONO (-715 2860);
FORCEPROP 0 LASTPIN (-725 2900) $PN 26
J 0
(-715 2910);
DISPLAY 0.680851 (-715 2910);
PAINT MONO (-715 2910);
FORCEPROP 0 LASTPIN (-725 2950) $PN 28
J 0
(-715 2960);
DISPLAY 0.680851 (-715 2960);
PAINT MONO (-715 2960);
FORCEPROP 0 LASTPIN (-725 3000) $PN 30
J 0
(-715 3010);
DISPLAY 0.680851 (-715 3010);
PAINT MONO (-715 3010);
FORCEPROP 0 LASTPIN (-725 3050) $PN 32
J 0
(-715 3060);
DISPLAY 0.680851 (-715 3060);
PAINT MONO (-715 3060);
FORCEPROP 0 LASTPIN (-725 3100) $PN 35
J 0
(-715 3110);
DISPLAY 0.680851 (-715 3110);
PAINT MONO (-715 3110);
FORCEPROP 0 LASTPIN (-725 3150) $PN 37
J 0
(-715 3160);
DISPLAY 0.680851 (-715 3160);
PAINT MONO (-715 3160);
FORCEPROP 0 LASTPIN (-725 3200) $PN 39
J 0
(-715 3210);
DISPLAY 0.680851 (-715 3210);
PAINT MONO (-715 3210);
FORCEPROP 0 LASTPIN (-725 3250) $PN 41
J 0
(-715 3260);
DISPLAY 0.680851 (-715 3260);
PAINT MONO (-715 3260);
FORCEPROP 0 LASTPIN (-725 3300) $PN 43
J 0
(-715 3310);
DISPLAY 0.680851 (-715 3310);
PAINT MONO (-715 3310);
FORCEPROP 0 LASTPIN (-725 3350) $PN 46
J 0
(-715 3360);
DISPLAY 0.680851 (-715 3360);
PAINT MONO (-715 3360);
FORCEPROP 0 LASTPIN (-725 3400) $PN 48
J 0
(-715 3410);
DISPLAY 0.680851 (-715 3410);
PAINT MONO (-715 3410);
FORCEPROP 0 LASTPIN (-725 3450) $PN 50
J 0
(-715 3460);
DISPLAY 0.680851 (-715 3460);
PAINT MONO (-715 3460);
FORCEPROP 0 LASTPIN (-725 3500) $PN 52
J 0
(-715 3510);
DISPLAY 0.680851 (-715 3510);
PAINT MONO (-715 3510);
FORCEPROP 0 LASTPIN (-725 3550) $PN 54
J 0
(-715 3560);
DISPLAY 0.680851 (-715 3560);
PAINT MONO (-715 3560);
FORCEPROP 0 LASTPIN (-725 3600) $PN 57
J 0
(-715 3610);
DISPLAY 0.680851 (-715 3610);
PAINT MONO (-715 3610);
FORCEPROP 0 LASTPIN (-725 3650) $PN 59
J 0
(-715 3660);
DISPLAY 0.680851 (-715 3660);
PAINT MONO (-715 3660);
FORCEPROP 0 LASTPIN (-725 3700) $PN 61
J 0
(-715 3710);
DISPLAY 0.680851 (-715 3710);
PAINT MONO (-715 3710);
FORCEPROP 0 LASTPIN (-725 3750) $PN 63
J 0
(-715 3760);
DISPLAY 0.680851 (-715 3760);
PAINT MONO (-715 3760);
FORCEPROP 0 LASTPIN (-725 3800) $PN 65
J 0
(-715 3810);
DISPLAY 0.680851 (-715 3810);
PAINT MONO (-715 3810);
FORCEPROP 0 LASTPIN (-725 3850) $PN 67
J 0
(-715 3860);
DISPLAY 0.680851 (-715 3860);
PAINT MONO (-715 3860);
FORCEPROP 0 LASTPIN (-725 3900) $PN 69
J 0
(-715 3910);
DISPLAY 0.680851 (-715 3910);
PAINT MONO (-715 3910);
FORCEPROP 0 LASTPIN (-725 3950) $PN 71
J 0
(-715 3960);
DISPLAY 0.680851 (-715 3960);
PAINT MONO (-715 3960);
FORCEPROP 0 LASTPIN (-725 4000) $PN 73
J 0
(-715 4010);
DISPLAY 0.680851 (-715 4010);
PAINT MONO (-715 4010);
FORCEPROP 0 LASTPIN (-725 4050) $PN 75
J 0
(-715 4060);
DISPLAY 0.680851 (-715 4060);
PAINT MONO (-715 4060);
FORCEPROP 0 LASTPIN (-725 4100) $PN 77
J 0
(-715 4110);
DISPLAY 0.680851 (-715 4110);
PAINT MONO (-715 4110);
FORCEPROP 0 LASTPIN (-725 4150) $PN 79
J 0
(-715 4160);
DISPLAY 0.680851 (-715 4160);
PAINT MONO (-715 4160);
FORCEPROP 0 LASTPIN (-725 4200) $PN 81
J 0
(-715 4210);
DISPLAY 0.680851 (-715 4210);
PAINT MONO (-715 4210);
FORCEPROP 0 LASTPIN (-725 4250) $PN 83
J 0
(-715 4260);
DISPLAY 0.680851 (-715 4260);
PAINT MONO (-715 4260);
FORCEPROP 0 LASTPIN (-725 4300) $PN 85
J 0
(-715 4310);
DISPLAY 0.680851 (-715 4310);
PAINT MONO (-715 4310);
FORCEPROP 0 LASTPIN (-725 4350) $PN 88
J 0
(-715 4360);
DISPLAY 0.680851 (-715 4360);
PAINT MONO (-715 4360);
FORCEPROP 0 LASTPIN (-725 4400) $PN 90
J 0
(-715 4410);
DISPLAY 0.680851 (-715 4410);
PAINT MONO (-715 4410);
FORCEPROP 0 LASTPIN (-725 4450) $PN 92
J 0
(-715 4460);
DISPLAY 0.680851 (-715 4460);
PAINT MONO (-715 4460);
FORCEPROP 0 LASTPIN (-725 4500) $PN 95
J 0
(-715 4510);
DISPLAY 0.680851 (-715 4510);
PAINT MONO (-715 4510);
FORCEPROP 0 LASTPIN (-725 4550) $PN 97
J 0
(-715 4560);
DISPLAY 0.680851 (-715 4560);
PAINT MONO (-715 4560);
FORCEPROP 0 LASTPIN (-725 4600) $PN 99
J 0
(-715 4610);
DISPLAY 0.680851 (-715 4610);
PAINT MONO (-715 4610);
FORCEPROP 0 LASTPIN (-725 4650) $PN 101
J 0
(-715 4660);
DISPLAY 0.680851 (-715 4660);
PAINT MONO (-715 4660);
FORCEPROP 0 LASTPIN (-725 4700) $PN 103
J 0
(-715 4710);
DISPLAY 0.680851 (-715 4710);
PAINT MONO (-715 4710);
FORCEPROP 0 LASTPIN (-725 4750) $PN 106
J 0
(-715 4760);
DISPLAY 0.680851 (-715 4760);
PAINT MONO (-715 4760);
FORCEPROP 0 LASTPIN (-725 4800) $PN 108
J 0
(-715 4810);
DISPLAY 0.680851 (-715 4810);
PAINT MONO (-715 4810);
FORCEPROP 0 LASTPIN (-725 4850) $PN 110
J 0
(-715 4860);
DISPLAY 0.680851 (-715 4860);
PAINT MONO (-715 4860);
FORCEPROP 0 LASTPIN (-725 4900) $PN 112
J 0
(-715 4910);
DISPLAY 0.680851 (-715 4910);
PAINT MONO (-715 4910);
FORCEPROP 0 LASTPIN (-725 4950) $PN 114
J 0
(-715 4960);
DISPLAY 0.680851 (-715 4960);
PAINT MONO (-715 4960);
FORCEPROP 0 LASTPIN (-725 5000) $PN 117
J 0
(-715 5010);
DISPLAY 0.680851 (-715 5010);
PAINT MONO (-715 5010);
FORCEPROP 0 LASTPIN (-725 5050) $PN 119
J 0
(-715 5060);
DISPLAY 0.680851 (-715 5060);
PAINT MONO (-715 5060);
FORCEPROP 0 LASTPIN (-725 5100) $PN 121
J 0
(-715 5110);
DISPLAY 0.680851 (-715 5110);
PAINT MONO (-715 5110);
FORCEPROP 0 LASTPIN (-725 5150) $PN 123
J 0
(-715 5160);
DISPLAY 0.680851 (-715 5160);
PAINT MONO (-715 5160);
FORCEPROP 0 LASTPIN (-725 5200) $PN 125
J 0
(-715 5210);
DISPLAY 0.680851 (-715 5210);
PAINT MONO (-715 5210);
FORCEPROP 0 LASTPIN (-725 5250) $PN 128
J 0
(-715 5260);
DISPLAY 0.680851 (-715 5260);
PAINT MONO (-715 5260);
FORCEPROP 0 LASTPIN (-725 5300) $PN 130
J 0
(-715 5310);
DISPLAY 0.680851 (-715 5310);
PAINT MONO (-715 5310);
FORCEPROP 0 LASTPIN (-725 5350) $PN 132
J 0
(-715 5360);
DISPLAY 0.680851 (-715 5360);
PAINT MONO (-715 5360);
FORCEPROP 0 LASTPIN (-725 5400) $PN 134
J 0
(-715 5410);
DISPLAY 0.680851 (-715 5410);
PAINT MONO (-715 5410);
FORCEPROP 0 LASTPIN (-725 5450) $PN 136
J 0
(-715 5460);
DISPLAY 0.680851 (-715 5460);
PAINT MONO (-715 5460);
FORCEPROP 0 LASTPIN (-725 5500) $PN 139
J 0
(-715 5510);
DISPLAY 0.680851 (-715 5510);
PAINT MONO (-715 5510);
FORCEPROP 0 LASTPIN (-725 5550) $PN 141
J 0
(-715 5560);
DISPLAY 0.680851 (-715 5560);
PAINT MONO (-715 5560);
FORCEPROP 0 LASTPIN (-725 5600) $PN 143
J 0
(-715 5610);
DISPLAY 0.680851 (-715 5610);
PAINT MONO (-715 5610);
FORCEPROP 0 LASTPIN (-1925 2350) $PN 151
J 2
(-1935 2360);
DISPLAY 0.680851 (-1935 2360);
PAINT MONO (-1935 2360);
FORCEPROP 0 LASTPIN (-1925 2400) $PN 153
J 2
(-1935 2410);
DISPLAY 0.680851 (-1935 2410);
PAINT MONO (-1935 2410);
FORCEPROP 0 LASTPIN (-1925 2450) $PN 155
J 2
(-1935 2460);
DISPLAY 0.680851 (-1935 2460);
PAINT MONO (-1935 2460);
FORCEPROP 0 LASTPIN (-1925 2500) $PN 158
J 2
(-1935 2510);
DISPLAY 0.680851 (-1935 2510);
PAINT MONO (-1935 2510);
FORCEPROP 0 LASTPIN (-1925 2550) $PN 160
J 2
(-1935 2560);
DISPLAY 0.680851 (-1935 2560);
PAINT MONO (-1935 2560);
FORCEPROP 0 LASTPIN (-1925 2600) $PN 162
J 2
(-1935 2610);
DISPLAY 0.680851 (-1935 2610);
PAINT MONO (-1935 2610);
FORCEPROP 0 LASTPIN (-1925 2650) $PN 164
J 2
(-1935 2660);
DISPLAY 0.680851 (-1935 2660);
PAINT MONO (-1935 2660);
FORCEPROP 0 LASTPIN (-1925 2700) $PN 166
J 2
(-1935 2710);
DISPLAY 0.680851 (-1935 2710);
PAINT MONO (-1935 2710);
FORCEPROP 0 LASTPIN (-1925 2750) $PN 169
J 2
(-1935 2760);
DISPLAY 0.680851 (-1935 2760);
PAINT MONO (-1935 2760);
FORCEPROP 0 LASTPIN (-1925 2800) $PN 171
J 2
(-1935 2810);
DISPLAY 0.680851 (-1935 2810);
PAINT MONO (-1935 2810);
FORCEPROP 0 LASTPIN (-1925 2850) $PN 173
J 2
(-1935 2860);
DISPLAY 0.680851 (-1935 2860);
PAINT MONO (-1935 2860);
FORCEPROP 0 LASTPIN (-1925 2900) $PN 175
J 2
(-1935 2910);
DISPLAY 0.680851 (-1935 2910);
PAINT MONO (-1935 2910);
FORCEPROP 0 LASTPIN (-1925 2950) $PN 177
J 2
(-1935 2960);
DISPLAY 0.680851 (-1935 2960);
PAINT MONO (-1935 2960);
FORCEPROP 0 LASTPIN (-1925 3000) $PN 180
J 2
(-1935 3010);
DISPLAY 0.680851 (-1935 3010);
PAINT MONO (-1935 3010);
FORCEPROP 0 LASTPIN (-1925 3050) $PN 182
J 2
(-1935 3060);
DISPLAY 0.680851 (-1935 3060);
PAINT MONO (-1935 3060);
FORCEPROP 0 LASTPIN (-1925 3100) $PN 184
J 2
(-1935 3110);
DISPLAY 0.680851 (-1935 3110);
PAINT MONO (-1935 3110);
FORCEPROP 0 LASTPIN (-1925 3150) $PN 186
J 2
(-1935 3160);
DISPLAY 0.680851 (-1935 3160);
PAINT MONO (-1935 3160);
FORCEPROP 0 LASTPIN (-1925 3200) $PN 188
J 2
(-1935 3210);
DISPLAY 0.680851 (-1935 3210);
PAINT MONO (-1935 3210);
FORCEPROP 0 LASTPIN (-1925 3250) $PN 191
J 2
(-1935 3260);
DISPLAY 0.680851 (-1935 3260);
PAINT MONO (-1935 3260);
FORCEPROP 0 LASTPIN (-1925 3300) $PN 193
J 2
(-1935 3310);
DISPLAY 0.680851 (-1935 3310);
PAINT MONO (-1935 3310);
FORCEPROP 0 LASTPIN (-1925 3350) $PN 195
J 2
(-1935 3360);
DISPLAY 0.680851 (-1935 3360);
PAINT MONO (-1935 3360);
FORCEPROP 0 LASTPIN (-1925 3400) $PN 197
J 2
(-1935 3410);
DISPLAY 0.680851 (-1935 3410);
PAINT MONO (-1935 3410);
FORCEPROP 0 LASTPIN (-1925 3450) $PN 199
J 2
(-1935 3460);
DISPLAY 0.680851 (-1935 3460);
PAINT MONO (-1935 3460);
FORCEPROP 0 LASTPIN (-1925 3500) $PN 202
J 2
(-1935 3510);
DISPLAY 0.680851 (-1935 3510);
PAINT MONO (-1935 3510);
FORCEPROP 0 LASTPIN (-1925 3550) $PN 204
J 2
(-1935 3560);
DISPLAY 0.680851 (-1935 3560);
PAINT MONO (-1935 3560);
FORCEPROP 0 LASTPIN (-1925 3600) $PN 206
J 2
(-1935 3610);
DISPLAY 0.680851 (-1935 3610);
PAINT MONO (-1935 3610);
FORCEPROP 0 LASTPIN (-1925 3650) $PN 208
J 2
(-1935 3660);
DISPLAY 0.680851 (-1935 3660);
PAINT MONO (-1935 3660);
FORCEPROP 0 LASTPIN (-1925 3700) $PN 210
J 2
(-1935 3710);
DISPLAY 0.680851 (-1935 3710);
PAINT MONO (-1935 3710);
FORCEPROP 0 LASTPIN (-1925 3750) $PN 212
J 2
(-1935 3760);
DISPLAY 0.680851 (-1935 3760);
PAINT MONO (-1935 3760);
FORCEPROP 0 LASTPIN (-1925 3800) $PN 214
J 2
(-1935 3810);
DISPLAY 0.680851 (-1935 3810);
PAINT MONO (-1935 3810);
FORCEPROP 0 LASTPIN (-1925 3850) $PN 216
J 2
(-1935 3860);
DISPLAY 0.680851 (-1935 3860);
PAINT MONO (-1935 3860);
FORCEPROP 0 LASTPIN (-1925 3900) $PN 219
J 2
(-1935 3910);
DISPLAY 0.680851 (-1935 3910);
PAINT MONO (-1935 3910);
FORCEPROP 0 LASTPIN (-1925 3950) $PN 222
J 2
(-1935 3960);
DISPLAY 0.680851 (-1935 3960);
PAINT MONO (-1935 3960);
FORCEPROP 0 LASTPIN (-1925 4000) $PN 224
J 2
(-1935 4010);
DISPLAY 0.680851 (-1935 4010);
PAINT MONO (-1935 4010);
FORCEPROP 0 LASTPIN (-1925 4050) $PN 226
J 2
(-1935 4060);
DISPLAY 0.680851 (-1935 4060);
PAINT MONO (-1935 4060);
FORCEPROP 0 LASTPIN (-1925 4100) $PN 228
J 2
(-1935 4110);
DISPLAY 0.680851 (-1935 4110);
PAINT MONO (-1935 4110);
FORCEPROP 0 LASTPIN (-1925 4150) $PN 230
J 2
(-1935 4160);
DISPLAY 0.680851 (-1935 4160);
PAINT MONO (-1935 4160);
FORCEPROP 0 LASTPIN (-1925 4200) $PN 233
J 2
(-1935 4210);
DISPLAY 0.680851 (-1935 4210);
PAINT MONO (-1935 4210);
FORCEPROP 0 LASTPIN (-1925 4250) $PN 235
J 2
(-1935 4260);
DISPLAY 0.680851 (-1935 4260);
PAINT MONO (-1935 4260);
FORCEPROP 0 LASTPIN (-1925 4300) $PN 237
J 2
(-1935 4310);
DISPLAY 0.680851 (-1935 4310);
PAINT MONO (-1935 4310);
FORCEPROP 0 LASTPIN (-1925 4350) $PN 240
J 2
(-1935 4360);
DISPLAY 0.680851 (-1935 4360);
PAINT MONO (-1935 4360);
FORCEPROP 0 LASTPIN (-1925 4400) $PN 242
J 2
(-1935 4410);
DISPLAY 0.680851 (-1935 4410);
PAINT MONO (-1935 4410);
FORCEPROP 0 LASTPIN (-1925 4450) $PN 244
J 2
(-1935 4460);
DISPLAY 0.680851 (-1935 4460);
PAINT MONO (-1935 4460);
FORCEPROP 0 LASTPIN (-1925 4500) $PN 246
J 2
(-1935 4510);
DISPLAY 0.680851 (-1935 4510);
PAINT MONO (-1935 4510);
FORCEPROP 0 LASTPIN (-1925 4550) $PN 248
J 2
(-1935 4560);
DISPLAY 0.680851 (-1935 4560);
PAINT MONO (-1935 4560);
FORCEPROP 0 LASTPIN (-1925 4600) $PN 251
J 2
(-1935 4610);
DISPLAY 0.680851 (-1935 4610);
PAINT MONO (-1935 4610);
FORCEPROP 0 LASTPIN (-1925 4650) $PN 253
J 2
(-1935 4660);
DISPLAY 0.680851 (-1935 4660);
PAINT MONO (-1935 4660);
FORCEPROP 0 LASTPIN (-1925 4700) $PN 255
J 2
(-1935 4710);
DISPLAY 0.680851 (-1935 4710);
PAINT MONO (-1935 4710);
FORCEPROP 0 LASTPIN (-1925 4750) $PN 257
J 2
(-1935 4760);
DISPLAY 0.680851 (-1935 4760);
PAINT MONO (-1935 4760);
FORCEPROP 0 LASTPIN (-1925 4800) $PN 259
J 2
(-1935 4810);
DISPLAY 0.680851 (-1935 4810);
PAINT MONO (-1935 4810);
FORCEPROP 0 LASTPIN (-1925 4850) $PN 262
J 2
(-1935 4860);
DISPLAY 0.680851 (-1935 4860);
PAINT MONO (-1935 4860);
FORCEPROP 0 LASTPIN (-1925 4900) $PN 264
J 2
(-1935 4910);
DISPLAY 0.680851 (-1935 4910);
PAINT MONO (-1935 4910);
FORCEPROP 0 LASTPIN (-1925 4950) $PN 266
J 2
(-1935 4960);
DISPLAY 0.680851 (-1935 4960);
PAINT MONO (-1935 4960);
FORCEPROP 0 LASTPIN (-1925 5000) $PN 268
J 2
(-1935 5010);
DISPLAY 0.680851 (-1935 5010);
PAINT MONO (-1935 5010);
FORCEPROP 0 LASTPIN (-1925 5050) $PN 270
J 2
(-1935 5060);
DISPLAY 0.680851 (-1935 5060);
PAINT MONO (-1935 5060);
FORCEPROP 0 LASTPIN (-1925 5100) $PN 273
J 2
(-1935 5110);
DISPLAY 0.680851 (-1935 5110);
PAINT MONO (-1935 5110);
FORCEPROP 0 LASTPIN (-1925 5150) $PN 275
J 2
(-1935 5160);
DISPLAY 0.680851 (-1935 5160);
PAINT MONO (-1935 5160);
FORCEPROP 0 LASTPIN (-1925 5200) $PN 277
J 2
(-1935 5210);
DISPLAY 0.680851 (-1935 5210);
PAINT MONO (-1935 5210);
FORCEPROP 0 LASTPIN (-1925 5250) $PN 279
J 2
(-1935 5260);
DISPLAY 0.680851 (-1935 5260);
PAINT MONO (-1935 5260);
FORCEPROP 0 LASTPIN (-1925 5300) $PN 281
J 2
(-1935 5310);
DISPLAY 0.680851 (-1935 5310);
PAINT MONO (-1935 5310);
FORCEPROP 0 LASTPIN (-1925 5350) $PN 284
J 2
(-1935 5360);
DISPLAY 0.680851 (-1935 5360);
PAINT MONO (-1935 5360);
FORCEPROP 0 LASTPIN (-1925 5400) $PN 286
J 2
(-1935 5410);
DISPLAY 0.680851 (-1935 5410);
PAINT MONO (-1935 5410);
FORCEPROP 0 LASTPIN (-1925 5450) $PN 288
J 2
(-1935 5460);
DISPLAY 0.680851 (-1935 5460);
PAINT MONO (-1935 5460);
FORCEPROP 1 LAST MATERIAL IO
J 0
(-1775 5775);
DISPLAY 0.468085 (-1775 5775);
PAINT SKYBLUE (-1775 5775);
FORCEPROP 2 LAST PART_TYPE SMLF
J 0
(-1775 6025);
DISPLAY 1.021277 (-1775 6025);
FORCEPROP 2 LAST VALUE SCONN288_DDR506112002KQ
J 0
(-1775 5975);
DISPLAY 0.489362 (-1775 5975);
PAINT SKYBLUE (-1775 5975);
FORCEPROP 2 LAST CDS_LIB pure_quanta
J 0
(-1325 3950);
DISPLAY INVISIBLE (-1325 3950);
FORCEPROP 1 LAST NEEDS_NO_SIZE TRUE
J 0
(-1325 3950);
DISPLAY 0.723404 (-1325 3950);
PAINT GREEN (-1325 3950);
DISPLAY INVISIBLE (-1325 3950);
FORCEPROP 1 LAST CDS_LMAN_SYM_OUTLINE -450,1800,450,-1750
J 0
(-1325 3950);
DISPLAY 0.468085 (-1325 3950);
PAINT GREEN (-1325 3950);
DISPLAY INVISIBLE (-1325 3950);
FORCEPROP 1 LAST PATH I352
J 0
(-1325 3950);
DISPLAY 0.723404 (-1325 3950);
PAINT GREEN (-1325 3950);
DISPLAY INVISIBLE (-1325 3950);
FORCEPROP 1 LAST PART_NUMBER DFHST8FS479
J 0
(-1775 5850);
DISPLAY 0.468085 (-1775 5850);
PAINT SKYBLUE (-1775 5850);
DISPLAY INVISIBLE (-1775 5850);
FORCEADD OFFPAGE..5
(-8175 3375);
FORCEPROP 2 LAST $XR0 15 
J 0
(-8429 3375);
DISPLAY 0.638298 (-8429 3375);
PAINT MONO (-8429 3375);
FORCEPROP 2 LAST CDS_LIB mstr_standard
J 0
(-8175 3375);
DISPLAY INVISIBLE (-8175 3375);
FORCEPROP 1 LAST OFFPAGE TRUE
J 0
(-7850 3250);
DISPLAY 0.872340 (-7850 3250);
PAINT GREEN (-7850 3250);
DISPLAY INVISIBLE (-7850 3250);
FORCEPROP 1 LAST COMMENT_BODY TRUE
J 0
(-8075 3300);
DISPLAY 0.872340 (-8075 3300);
PAINT GREEN (-8075 3300);
DISPLAY INVISIBLE (-8075 3300);
FORCEPROP 2 LAST PATH I353
J 0
(-8125 3450);
DISPLAY 1.021277 (-8125 3450);
DISPLAY INVISIBLE (-8125 3450);
FORCEADD Q_CAP..1
R 2
(-8650 3575);
FORCEPROP 1 LAST LOCATION C108
J 2
(-8700 3675);
DISPLAY 0.489362 (-8700 3675);
PAINT SKYBLUE (-8700 3675);
FORCEPROP 0 LAST $SEC 1
J 0
(-8700 3725);
DISPLAY 0.680851 (-8700 3725);
PAINT MONO (-8700 3725);
DISPLAY INVISIBLE (-8700 3725);
FORCEPROP 0 LAST CDS_SEC 1
J 0
(-8700 3725);
DISPLAY 1.021277 (-8700 3725);
DISPLAY INVISIBLE (-8700 3725);
FORCEPROP 1 LASTPIN (-8650 3675) $PN 1
J 2
(-8660 3655);
DISPLAY 0.489362 (-8660 3655);
PAINT MONO (-8660 3655);
FORCEPROP 1 LASTPIN (-8650 3475) $PN 2
J 2
(-8660 3455);
DISPLAY 0.489362 (-8660 3455);
PAINT MONO (-8660 3455);
FORCEPROP 1 LAST VALUE 0.1UF
J 2
(-8700 3625);
DISPLAY 0.489362 (-8700 3625);
PAINT SKYBLUE (-8700 3625);
FORCEPROP 1 LAST MATERIAL X7R
J 2
(-8700 3475);
DISPLAY 0.489362 (-8700 3475);
PAINT SKYBLUE (-8700 3475);
FORCEPROP 1 LAST PACK_TYPE 0402
J 2
(-8700 3375);
DISPLAY 0.489362 (-8700 3375);
PAINT SKYBLUE (-8700 3375);
FORCEPROP 1 LAST TOLERANCE 10%
J 2
(-8700 3525);
DISPLAY 0.489362 (-8700 3525);
PAINT SKYBLUE (-8700 3525);
FORCEPROP 1 LAST VOLTAGE 25V
J 2
(-8700 3575);
DISPLAY 0.489362 (-8700 3575);
PAINT SKYBLUE (-8700 3575);
FORCEPROP 2 LAST CDS_LIB pure_quanta
J 0
(-8650 3575);
DISPLAY INVISIBLE (-8650 3575);
FORCEPROP 0 LAST BOM_COST MEM
J 2
(-8705 3720);
DISPLAY 0.595745 (-8705 3720);
PAINT MONO (-8705 3720);
DISPLAY INVISIBLE (-8705 3720);
FORCEPROP 2 LAST ROOM 
J 2
(-8705 3720);
DISPLAY 0.595745 (-8705 3720);
PAINT RED (-8705 3720);
DISPLAY INVISIBLE (-8705 3720);
FORCEPROP 1 LAST PATH I361
J 2
(-8700 3725);
DISPLAY 0.978723 (-8700 3725);
PAINT WHITE (-8700 3725);
DISPLAY INVISIBLE (-8700 3725);
FORCEPROP 1 LAST PART_NUMBER CH4104K1B00
J 2
(-8700 3425);
DISPLAY 0.489362 (-8700 3425);
PAINT SKYBLUE (-8700 3425);
DISPLAY INVISIBLE (-8700 3425);
FORCEADD GND..1
(-8650 3350);
FORCEPROP 3 LASTPIN (-8650 3400) SIG_NAME GND\g
J 0
(-8640 3410);
DISPLAY 0.659574 (-8640 3410);
PAINT MONO (-8640 3410);
DISPLAY INVISIBLE (-8640 3410);
FORCEPROP 2 LAST ROOM MEM_EFGH_DECOUPLING_CAPS
J 0
(-8625 3425);
DISPLAY 0.659574 (-8625 3425);
PAINT RED (-8625 3425);
DISPLAY INVISIBLE (-8625 3425);
FORCEPROP 1 LAST VOLTAGE 0
J 0
(-8670 3445);
DISPLAY 0.829787 (-8670 3445);
PAINT SKYBLUE (-8670 3445);
DISPLAY INVISIBLE (-8670 3445);
FORCEPROP 2 LAST BOM_COST MEM
J 0
(-8625 3475);
DISPLAY 0.659574 (-8625 3475);
DISPLAY INVISIBLE (-8625 3475);
FORCEPROP 1 LAST SIZE 1B
J 0
(-8575 3300);
DISPLAY 0.723404 (-8575 3300);
PAINT GREEN (-8575 3300);
DISPLAY INVISIBLE (-8575 3300);
FORCEPROP 2 LAST CDS_LIB mstr_symbols
J 0
(-8650 3350);
DISPLAY 0.808511 (-8650 3350);
DISPLAY INVISIBLE (-8650 3350);
FORCEPROP 1 LAST BODY_TYPE PLUMBING
J 0
(-8695 3307);
DISPLAY 0.276596 (-8695 3307);
PAINT GREEN (-8695 3307);
DISPLAY INVISIBLE (-8695 3307);
FORCEPROP 1 LAST HDL_POWER GND
J 0
(-8650 3500);
DISPLAY 0.723404 (-8650 3500);
PAINT GREEN (-8650 3500);
DISPLAY INVISIBLE (-8650 3500);
FORCEPROP 1 LAST PATH I362
J 0
(-8575 3350);
DISPLAY 0.872340 (-8575 3350);
PAINT AQUA (-8575 3350);
DISPLAY INVISIBLE (-8575 3350);
FORCEADD OFFPAGE..6
(-9050 2475);
FORCEPROP 2 LAST $XR4 90 
J 0
(-9329 2511);
DISPLAY 0.638298 (-9329 2511);
PAINT MONO (-9329 2511);
FORCEPROP 2 LAST $XR3 89 
J 0
(-9419 2439);
DISPLAY 0.638298 (-9419 2439);
PAINT MONO (-9419 2439);
FORCEPROP 2 LAST $XR2 88 
J 0
(-9329 2439);
DISPLAY 0.638298 (-9329 2439);
PAINT MONO (-9329 2439);
FORCEPROP 2 LAST $XR1 87 
J 0
(-9419 2475);
DISPLAY 0.638298 (-9419 2475);
PAINT MONO (-9419 2475);
FORCEPROP 2 LAST $XR0 86 
J 0
(-9329 2475);
DISPLAY 0.638298 (-9329 2475);
PAINT MONO (-9329 2475);
FORCEPROP 2 LAST CDS_LIB mstr_standard
J 0
(-9050 2475);
DISPLAY INVISIBLE (-9050 2475);
FORCEPROP 1 LAST OFFPAGE TRUE
J 0
(-8725 2350);
DISPLAY 0.872340 (-8725 2350);
PAINT GREEN (-8725 2350);
DISPLAY INVISIBLE (-8725 2350);
FORCEPROP 1 LAST COMMENT_BODY TRUE
J 0
(-8950 2400);
DISPLAY 0.872340 (-8950 2400);
PAINT GREEN (-8950 2400);
DISPLAY INVISIBLE (-8950 2400);
FORCEPROP 2 LAST PATH I363
J 0
(-9000 2550);
DISPLAY 1.021277 (-9000 2550);
DISPLAY INVISIBLE (-9000 2550);
FORCEADD Q_RES..1
R 2
(-8550 2475);
FORCEPROP 1 LAST LOCATION R296
J 2
(-8500 2525);
DISPLAY 0.489362 (-8500 2525);
PAINT SKYBLUE (-8500 2525);
FORCEPROP 0 LAST $SEC 1
J 0
(-8500 2575);
DISPLAY 0.680851 (-8500 2575);
PAINT MONO (-8500 2575);
DISPLAY INVISIBLE (-8500 2575);
FORCEPROP 0 LAST CDS_SEC 1
J 0
(-8500 2575);
DISPLAY 1.021277 (-8500 2575);
DISPLAY INVISIBLE (-8500 2575);
FORCEPROP 1 LASTPIN (-8450 2475) $PN 1
J 2
(-8462 2487);
DISPLAY 0.489362 (-8462 2487);
PAINT MONO (-8462 2487);
FORCEPROP 1 LASTPIN (-8650 2475) $PN 2
J 2
(-8612 2487);
DISPLAY 0.489362 (-8612 2487);
PAINT MONO (-8612 2487);
FORCEPROP 1 LAST VALUE 1K
J 0
(-8550 2425);
DISPLAY 0.489362 (-8550 2425);
PAINT SKYBLUE (-8550 2425);
FORCEPROP 1 LAST PACK_TYPE 0402LF
J 0
(-8725 2400);
DISPLAY 0.489362 (-8725 2400);
PAINT SKYBLUE (-8725 2400);
DISPLAY INVISIBLE (-8725 2400);
FORCEPROP 1 LAST MATERIAL CHIP
J 0
(-8725 2450);
DISPLAY 0.489362 (-8725 2450);
PAINT SKYBLUE (-8725 2450);
DISPLAY INVISIBLE (-8725 2450);
FORCEPROP 1 LAST WATTAGE 1/16W
J 0
(-8475 2400);
DISPLAY 0.489362 (-8475 2400);
PAINT SKYBLUE (-8475 2400);
DISPLAY INVISIBLE (-8475 2400);
FORCEPROP 2 LAST BOM_COST MEM
J 0
(-8575 2625);
DISPLAY 0.744681 (-8575 2625);
PAINT WHITE (-8575 2625);
DISPLAY INVISIBLE (-8575 2625);
FORCEPROP 2 LAST CDS_LIB pure_quanta
J 0
(-8550 2475);
DISPLAY INVISIBLE (-8550 2475);
FORCEPROP 1 LAST TOLERANCE 1%
J 2
(-8425 2450);
DISPLAY 0.489362 (-8425 2450);
PAINT SKYBLUE (-8425 2450);
DISPLAY INVISIBLE (-8425 2450);
FORCEPROP 2 LAST ROOM 
J 0
(-8575 2575);
DISPLAY 0.744681 (-8575 2575);
PAINT RED (-8575 2575);
DISPLAY INVISIBLE (-8575 2575);
FORCEPROP 1 LAST PATH I364
J 2
(-8500 2625);
DISPLAY 0.978723 (-8500 2625);
PAINT WHITE (-8500 2625);
DISPLAY INVISIBLE (-8500 2625);
FORCEPROP 1 LAST PART_NUMBER CS21002FB06
J 0
(-8650 2525);
DISPLAY 0.489362 (-8650 2525);
PAINT SKYBLUE (-8650 2525);
DISPLAY INVISIBLE (-8650 2525);
FORCEADD Q_RES..2
(-8425 2625);
FORCEPROP 1 LAST LOCATION R94
J 0
(-8380 2750);
DISPLAY 0.489362 (-8380 2750);
PAINT SKYBLUE (-8380 2750);
FORCEPROP 0 LAST $SEC 1
J 0
(-8375 2800);
DISPLAY 0.680851 (-8375 2800);
PAINT MONO (-8375 2800);
DISPLAY INVISIBLE (-8375 2800);
FORCEPROP 0 LAST CDS_SEC 1
J 0
(-8375 2800);
DISPLAY 1.021277 (-8375 2800);
DISPLAY INVISIBLE (-8375 2800);
FORCEPROP 1 LASTPIN (-8425 2725) $PN 1
J 0
(-8420 2687);
DISPLAY 0.489362 (-8420 2687);
PAINT MONO (-8420 2687);
FORCEPROP 1 LASTPIN (-8425 2525) $PN 2
J 0
(-8420 2535);
DISPLAY 0.489362 (-8420 2535);
PAINT MONO (-8420 2535);
FORCEPROP 1 LAST VALUE 1K
J 0
(-8380 2700);
DISPLAY 0.489362 (-8380 2700);
PAINT SKYBLUE (-8380 2700);
FORCEPROP 1 LAST TOLERANCE 1%
J 0
(-8375 2675);
DISPLAY 0.489362 (-8375 2675);
PAINT SKYBLUE (-8375 2675);
FORCEPROP 1 LAST WATTAGE 1/16W
J 0
(-8375 2650);
DISPLAY 0.489362 (-8375 2650);
PAINT SKYBLUE (-8375 2650);
FORCEPROP 1 LAST PACK_TYPE 0402LF
J 0
(-8375 2575);
DISPLAY 0.489362 (-8375 2575);
PAINT SKYBLUE (-8375 2575);
FORCEPROP 1 LAST MATERIAL EMPTY
J 0
(-8375 2625);
DISPLAY 0.489362 (-8375 2625);
PAINT RED (-8375 2625);
FORCEPROP 2 LAST BOM_COST MEM
J 0
(-8375 2800);
DISPLAY 0.808511 (-8375 2800);
DISPLAY INVISIBLE (-8375 2800);
FORCEPROP 2 LAST CDS_LIB pure_quanta
J 0
(-8425 2625);
DISPLAY INVISIBLE (-8425 2625);
FORCEPROP 2 LAST ROOM 
J 0
(-8375 2850);
DISPLAY 0.808511 (-8375 2850);
PAINT RED (-8375 2850);
DISPLAY INVISIBLE (-8375 2850);
FORCEPROP 1 LAST PATH I365
J 0
(-8375 2800);
DISPLAY 0.978723 (-8375 2800);
PAINT WHITE (-8375 2800);
DISPLAY INVISIBLE (-8375 2800);
FORCEPROP 1 LAST PART_NUMBER CS21002FB06
J 0
(-8375 2600);
DISPLAY 0.489362 (-8375 2600);
PAINT SKYBLUE (-8375 2600);
DISPLAY INVISIBLE (-8375 2600);
FORCEADD VCC_CORE..1
(-8425 2800);
FORCEPROP 3 LASTPIN (-8425 2750) SIG_NAME P3V3\g
J 0
(-8415 2760);
DISPLAY 0.659574 (-8415 2760);
PAINT MONO (-8415 2760);
DISPLAY INVISIBLE (-8415 2760);
FORCEPROP 1 LAST HDL_POWER P3V3
J 1
(-8425 2850);
DISPLAY 0.489362 (-8425 2850);
PAINT GREEN (-8425 2850);
FORCEPROP 2 LAST ROOM PVCCINFAON_CPU0_CTRL
J 0
(-8425 2900);
DISPLAY 0.808511 (-8425 2900);
PAINT RED (-8425 2900);
DISPLAY INVISIBLE (-8425 2900);
FORCEPROP 0 LAST VOLTAGE 3.3
J 0
(-8700 2950);
DISPLAY 1.021277 (-8700 2950);
PAINT SKYBLUE (-8700 2950);
DISPLAY INVISIBLE (-8700 2950);
FORCEPROP 2 LAST CDS_LIB mstr_symbols
J 0
(-8425 2800);
DISPLAY INVISIBLE (-8425 2800);
FORCEPROP 1 LAST PATH I366
J 0
(-8375 2825);
DISPLAY 0.872340 (-8375 2825);
PAINT AQUA (-8375 2825);
DISPLAY INVISIBLE (-8375 2825);
FORCEADD OFFPAGE..2
(-2575 4875);
FORCEPROP 2 LAST $XR0 15 
J 0
(-2386 4875);
DISPLAY 0.638298 (-2386 4875);
PAINT MONO (-2386 4875);
FORCEPROP 2 LAST CDS_LIB mstr_standard
J 0
(-2575 4875);
DISPLAY 0.723404 (-2575 4875);
PAINT MONO (-2575 4875);
DISPLAY INVISIBLE (-2575 4875);
FORCEPROP 1 LAST OFFPAGE TRUE
J 0
(-2250 4750);
DISPLAY 0.723404 (-2250 4750);
PAINT GREEN (-2250 4750);
DISPLAY INVISIBLE (-2250 4750);
FORCEPROP 1 LAST COMMENT_BODY TRUE
J 0
(-2620 4780);
DISPLAY 0.872340 (-2620 4780);
PAINT GREEN (-2620 4780);
DISPLAY INVISIBLE (-2620 4780);
FORCEPROP 2 LAST PATH I368
J 0
(-2375 4925);
DISPLAY 0.680851 (-2375 4925);
DISPLAY INVISIBLE (-2375 4925);
FORCEADD OFFPAGE..2
(-2575 4825);
FORCEPROP 2 LAST $XR0 15 
J 0
(-2386 4825);
DISPLAY 0.638298 (-2386 4825);
PAINT MONO (-2386 4825);
FORCEPROP 2 LAST CDS_LIB mstr_standard
J 0
(-2575 4825);
DISPLAY 0.723404 (-2575 4825);
PAINT MONO (-2575 4825);
DISPLAY INVISIBLE (-2575 4825);
FORCEPROP 1 LAST OFFPAGE TRUE
J 0
(-2250 4700);
DISPLAY 0.723404 (-2250 4700);
PAINT GREEN (-2250 4700);
DISPLAY INVISIBLE (-2250 4700);
FORCEPROP 1 LAST COMMENT_BODY TRUE
J 0
(-2620 4730);
DISPLAY 0.872340 (-2620 4730);
PAINT GREEN (-2620 4730);
DISPLAY INVISIBLE (-2620 4730);
FORCEPROP 2 LAST PATH I369
J 0
(-2375 4875);
DISPLAY 0.680851 (-2375 4875);
DISPLAY INVISIBLE (-2375 4875);
FORCEADD OFFPAGE..2
(-2575 3825);
FORCEPROP 2 LAST $XR0 15 
J 0
(-2386 3825);
DISPLAY 0.638298 (-2386 3825);
PAINT MONO (-2386 3825);
FORCEPROP 2 LAST CDS_LIB mstr_standard
J 0
(-2575 3825);
DISPLAY 0.723404 (-2575 3825);
PAINT MONO (-2575 3825);
DISPLAY INVISIBLE (-2575 3825);
FORCEPROP 1 LAST OFFPAGE TRUE
J 0
(-2250 3700);
DISPLAY 0.723404 (-2250 3700);
PAINT GREEN (-2250 3700);
DISPLAY INVISIBLE (-2250 3700);
FORCEPROP 1 LAST COMMENT_BODY TRUE
J 0
(-2620 3730);
DISPLAY 0.872340 (-2620 3730);
PAINT GREEN (-2620 3730);
DISPLAY INVISIBLE (-2620 3730);
FORCEPROP 2 LAST PATH I370
J 0
(-2375 3875);
DISPLAY 0.680851 (-2375 3875);
DISPLAY INVISIBLE (-2375 3875);
FORCEADD OFFPAGE..2
(-2575 3775);
FORCEPROP 2 LAST $XR0 15 
J 0
(-2386 3775);
DISPLAY 0.638298 (-2386 3775);
PAINT MONO (-2386 3775);
FORCEPROP 2 LAST CDS_LIB mstr_standard
J 0
(-2575 3775);
DISPLAY 0.723404 (-2575 3775);
PAINT MONO (-2575 3775);
DISPLAY INVISIBLE (-2575 3775);
FORCEPROP 1 LAST OFFPAGE TRUE
J 0
(-2250 3650);
DISPLAY 0.723404 (-2250 3650);
PAINT GREEN (-2250 3650);
DISPLAY INVISIBLE (-2250 3650);
FORCEPROP 1 LAST COMMENT_BODY TRUE
J 0
(-2620 3680);
DISPLAY 0.872340 (-2620 3680);
PAINT GREEN (-2620 3680);
DISPLAY INVISIBLE (-2620 3680);
FORCEPROP 2 LAST PATH I371
J 0
(-2375 3825);
DISPLAY 0.680851 (-2375 3825);
DISPLAY INVISIBLE (-2375 3825);
FORCEADD TAP..1
(-3375 4775);
FORCEPROP 3 LASTPIN (-3425 4775) SIG_NAME M_F_CPU0_SA_DQS_DN<9>
J 0
(-3415 4785);
DISPLAY 0.659574 (-3415 4785);
PAINT MONO (-3415 4785);
DISPLAY INVISIBLE (-3415 4785);
FORCEPROP 1 LASTPIN (-3425 4775) BN 9
J 0
(-3437 4783);
DISPLAY 0.489362 (-3437 4783);
PAINT GREEN (-3437 4783);
FORCEPROP 2 LAST CDS_LIB mstr_standard
J 0
(-3375 4775);
DISPLAY 0.723404 (-3375 4775);
PAINT MONO (-3375 4775);
DISPLAY INVISIBLE (-3375 4775);
FORCEPROP 1 LAST BODY_TYPE PLUMBING
J 0
(-3375 4825);
DISPLAY 0.872340 (-3375 4825);
PAINT GREEN (-3375 4825);
DISPLAY INVISIBLE (-3375 4825);
FORCEPROP 1 LAST HDL_TAP TRUE
J 0
(-3050 4650);
DISPLAY 0.872340 (-3050 4650);
DISPLAY INVISIBLE (-3050 4650);
FORCEPROP 1 LAST PATH I372
J 0
(-3377 4775);
DISPLAY 0.872340 (-3377 4775);
PAINT GREEN (-3377 4775);
DISPLAY INVISIBLE (-3377 4775);
FORCEADD TAP..1
(-3375 4675);
FORCEPROP 3 LASTPIN (-3425 4675) SIG_NAME M_F_CPU0_SA_DQS_DN<8>
J 0
(-3415 4685);
DISPLAY 0.659574 (-3415 4685);
PAINT MONO (-3415 4685);
DISPLAY INVISIBLE (-3415 4685);
FORCEPROP 1 LASTPIN (-3425 4675) BN 8
J 0
(-3437 4683);
DISPLAY 0.489362 (-3437 4683);
PAINT GREEN (-3437 4683);
FORCEPROP 2 LAST CDS_LIB mstr_standard
J 0
(-3375 4675);
DISPLAY 0.723404 (-3375 4675);
PAINT MONO (-3375 4675);
DISPLAY INVISIBLE (-3375 4675);
FORCEPROP 1 LAST BODY_TYPE PLUMBING
J 0
(-3375 4725);
DISPLAY 0.872340 (-3375 4725);
PAINT GREEN (-3375 4725);
DISPLAY INVISIBLE (-3375 4725);
FORCEPROP 1 LAST HDL_TAP TRUE
J 0
(-3050 4550);
DISPLAY 0.872340 (-3050 4550);
DISPLAY INVISIBLE (-3050 4550);
FORCEPROP 1 LAST PATH I373
J 0
(-3377 4675);
DISPLAY 0.872340 (-3377 4675);
PAINT GREEN (-3377 4675);
DISPLAY INVISIBLE (-3377 4675);
FORCEADD TAP..1
(-3375 4475);
FORCEPROP 3 LASTPIN (-3425 4475) SIG_NAME M_F_CPU0_SA_DQS_DN<6>
J 0
(-3415 4485);
DISPLAY 0.659574 (-3415 4485);
PAINT MONO (-3415 4485);
DISPLAY INVISIBLE (-3415 4485);
FORCEPROP 1 LASTPIN (-3425 4475) BN 6
J 0
(-3437 4483);
DISPLAY 0.489362 (-3437 4483);
PAINT GREEN (-3437 4483);
FORCEPROP 2 LAST CDS_LIB mstr_standard
J 0
(-3375 4475);
DISPLAY 0.723404 (-3375 4475);
PAINT MONO (-3375 4475);
DISPLAY INVISIBLE (-3375 4475);
FORCEPROP 1 LAST BODY_TYPE PLUMBING
J 0
(-3375 4525);
DISPLAY 0.872340 (-3375 4525);
PAINT GREEN (-3375 4525);
DISPLAY INVISIBLE (-3375 4525);
FORCEPROP 1 LAST HDL_TAP TRUE
J 0
(-3050 4350);
DISPLAY 0.872340 (-3050 4350);
DISPLAY INVISIBLE (-3050 4350);
FORCEPROP 1 LAST PATH I374
J 0
(-3377 4475);
DISPLAY 0.872340 (-3377 4475);
PAINT GREEN (-3377 4475);
DISPLAY INVISIBLE (-3377 4475);
FORCEADD TAP..1
(-3375 4575);
FORCEPROP 3 LASTPIN (-3425 4575) SIG_NAME M_F_CPU0_SA_DQS_DN<7>
J 0
(-3415 4585);
DISPLAY 0.659574 (-3415 4585);
PAINT MONO (-3415 4585);
DISPLAY INVISIBLE (-3415 4585);
FORCEPROP 1 LASTPIN (-3425 4575) BN 7
J 0
(-3437 4583);
DISPLAY 0.489362 (-3437 4583);
PAINT GREEN (-3437 4583);
FORCEPROP 2 LAST CDS_LIB mstr_standard
J 0
(-3375 4575);
DISPLAY 0.723404 (-3375 4575);
PAINT MONO (-3375 4575);
DISPLAY INVISIBLE (-3375 4575);
FORCEPROP 1 LAST BODY_TYPE PLUMBING
J 0
(-3375 4625);
DISPLAY 0.872340 (-3375 4625);
PAINT GREEN (-3375 4625);
DISPLAY INVISIBLE (-3375 4625);
FORCEPROP 1 LAST HDL_TAP TRUE
J 0
(-3050 4450);
DISPLAY 0.872340 (-3050 4450);
DISPLAY INVISIBLE (-3050 4450);
FORCEPROP 1 LAST PATH I375
J 0
(-3377 4575);
DISPLAY 0.872340 (-3377 4575);
PAINT GREEN (-3377 4575);
DISPLAY INVISIBLE (-3377 4575);
FORCEADD TAP..1
(-3375 4375);
FORCEPROP 3 LASTPIN (-3425 4375) SIG_NAME M_F_CPU0_SA_DQS_DN<5>
J 0
(-3415 4385);
DISPLAY 0.659574 (-3415 4385);
PAINT MONO (-3415 4385);
DISPLAY INVISIBLE (-3415 4385);
FORCEPROP 1 LASTPIN (-3425 4375) BN 5
J 0
(-3437 4383);
DISPLAY 0.489362 (-3437 4383);
PAINT GREEN (-3437 4383);
FORCEPROP 2 LAST CDS_LIB mstr_standard
J 0
(-3375 4375);
DISPLAY 0.723404 (-3375 4375);
PAINT MONO (-3375 4375);
DISPLAY INVISIBLE (-3375 4375);
FORCEPROP 1 LAST BODY_TYPE PLUMBING
J 0
(-3375 4425);
DISPLAY 0.872340 (-3375 4425);
PAINT GREEN (-3375 4425);
DISPLAY INVISIBLE (-3375 4425);
FORCEPROP 1 LAST HDL_TAP TRUE
J 0
(-3050 4250);
DISPLAY 0.872340 (-3050 4250);
DISPLAY INVISIBLE (-3050 4250);
FORCEPROP 1 LAST PATH I376
J 0
(-3377 4375);
DISPLAY 0.872340 (-3377 4375);
PAINT GREEN (-3377 4375);
DISPLAY INVISIBLE (-3377 4375);
FORCEADD TAP..1
(-3575 4725);
FORCEPROP 3 LASTPIN (-3625 4725) SIG_NAME M_F_CPU0_SA_DQS_DP<8>
J 0
(-3615 4735);
DISPLAY 0.659574 (-3615 4735);
PAINT MONO (-3615 4735);
DISPLAY INVISIBLE (-3615 4735);
FORCEPROP 1 LASTPIN (-3625 4725) BN 8
J 0
(-3637 4733);
DISPLAY 0.489362 (-3637 4733);
PAINT GREEN (-3637 4733);
FORCEPROP 2 LAST CDS_LIB mstr_standard
J 0
(-3575 4725);
DISPLAY 0.723404 (-3575 4725);
PAINT MONO (-3575 4725);
DISPLAY INVISIBLE (-3575 4725);
FORCEPROP 1 LAST BODY_TYPE PLUMBING
J 0
(-3575 4775);
DISPLAY 0.872340 (-3575 4775);
PAINT GREEN (-3575 4775);
DISPLAY INVISIBLE (-3575 4775);
FORCEPROP 1 LAST HDL_TAP TRUE
J 0
(-3250 4600);
DISPLAY 0.872340 (-3250 4600);
DISPLAY INVISIBLE (-3250 4600);
FORCEPROP 1 LAST PATH I377
J 0
(-3577 4725);
DISPLAY 0.872340 (-3577 4725);
PAINT GREEN (-3577 4725);
DISPLAY INVISIBLE (-3577 4725);
FORCEADD TAP..1
(-3575 4825);
FORCEPROP 3 LASTPIN (-3625 4825) SIG_NAME M_F_CPU0_SA_DQS_DP<9>
J 0
(-3615 4835);
DISPLAY 0.659574 (-3615 4835);
PAINT MONO (-3615 4835);
DISPLAY INVISIBLE (-3615 4835);
FORCEPROP 1 LASTPIN (-3625 4825) BN 9
J 0
(-3637 4833);
DISPLAY 0.489362 (-3637 4833);
PAINT GREEN (-3637 4833);
FORCEPROP 2 LAST CDS_LIB mstr_standard
J 0
(-3575 4825);
DISPLAY 0.723404 (-3575 4825);
PAINT MONO (-3575 4825);
DISPLAY INVISIBLE (-3575 4825);
FORCEPROP 1 LAST BODY_TYPE PLUMBING
J 0
(-3575 4875);
DISPLAY 0.872340 (-3575 4875);
PAINT GREEN (-3575 4875);
DISPLAY INVISIBLE (-3575 4875);
FORCEPROP 1 LAST HDL_TAP TRUE
J 0
(-3250 4700);
DISPLAY 0.872340 (-3250 4700);
DISPLAY INVISIBLE (-3250 4700);
FORCEPROP 1 LAST PATH I378
J 0
(-3577 4825);
DISPLAY 0.872340 (-3577 4825);
PAINT GREEN (-3577 4825);
DISPLAY INVISIBLE (-3577 4825);
FORCEADD TAP..1
(-3575 4625);
FORCEPROP 3 LASTPIN (-3625 4625) SIG_NAME M_F_CPU0_SA_DQS_DP<7>
J 0
(-3615 4635);
DISPLAY 0.659574 (-3615 4635);
PAINT MONO (-3615 4635);
DISPLAY INVISIBLE (-3615 4635);
FORCEPROP 1 LASTPIN (-3625 4625) BN 7
J 0
(-3637 4633);
DISPLAY 0.489362 (-3637 4633);
PAINT GREEN (-3637 4633);
FORCEPROP 2 LAST CDS_LIB mstr_standard
J 0
(-3575 4625);
DISPLAY 0.723404 (-3575 4625);
PAINT MONO (-3575 4625);
DISPLAY INVISIBLE (-3575 4625);
FORCEPROP 1 LAST BODY_TYPE PLUMBING
J 0
(-3575 4675);
DISPLAY 0.872340 (-3575 4675);
PAINT GREEN (-3575 4675);
DISPLAY INVISIBLE (-3575 4675);
FORCEPROP 1 LAST HDL_TAP TRUE
J 0
(-3250 4500);
DISPLAY 0.872340 (-3250 4500);
DISPLAY INVISIBLE (-3250 4500);
FORCEPROP 1 LAST PATH I379
J 0
(-3577 4625);
DISPLAY 0.872340 (-3577 4625);
PAINT GREEN (-3577 4625);
DISPLAY INVISIBLE (-3577 4625);
FORCEADD TAP..1
(-3575 4525);
FORCEPROP 3 LASTPIN (-3625 4525) SIG_NAME M_F_CPU0_SA_DQS_DP<6>
J 0
(-3615 4535);
DISPLAY 0.659574 (-3615 4535);
PAINT MONO (-3615 4535);
DISPLAY INVISIBLE (-3615 4535);
FORCEPROP 1 LASTPIN (-3625 4525) BN 6
J 0
(-3637 4533);
DISPLAY 0.489362 (-3637 4533);
PAINT GREEN (-3637 4533);
FORCEPROP 2 LAST CDS_LIB mstr_standard
J 0
(-3575 4525);
DISPLAY 0.723404 (-3575 4525);
PAINT MONO (-3575 4525);
DISPLAY INVISIBLE (-3575 4525);
FORCEPROP 1 LAST BODY_TYPE PLUMBING
J 0
(-3575 4575);
DISPLAY 0.872340 (-3575 4575);
PAINT GREEN (-3575 4575);
DISPLAY INVISIBLE (-3575 4575);
FORCEPROP 1 LAST HDL_TAP TRUE
J 0
(-3250 4400);
DISPLAY 0.872340 (-3250 4400);
DISPLAY INVISIBLE (-3250 4400);
FORCEPROP 1 LAST PATH I380
J 0
(-3577 4525);
DISPLAY 0.872340 (-3577 4525);
PAINT GREEN (-3577 4525);
DISPLAY INVISIBLE (-3577 4525);
FORCEADD TAP..1
(-3575 4425);
FORCEPROP 3 LASTPIN (-3625 4425) SIG_NAME M_F_CPU0_SA_DQS_DP<5>
J 0
(-3615 4435);
DISPLAY 0.659574 (-3615 4435);
PAINT MONO (-3615 4435);
DISPLAY INVISIBLE (-3615 4435);
FORCEPROP 1 LASTPIN (-3625 4425) BN 5
J 0
(-3637 4433);
DISPLAY 0.489362 (-3637 4433);
PAINT GREEN (-3637 4433);
FORCEPROP 2 LAST CDS_LIB mstr_standard
J 0
(-3575 4425);
DISPLAY 0.723404 (-3575 4425);
PAINT MONO (-3575 4425);
DISPLAY INVISIBLE (-3575 4425);
FORCEPROP 1 LAST BODY_TYPE PLUMBING
J 0
(-3575 4475);
DISPLAY 0.872340 (-3575 4475);
PAINT GREEN (-3575 4475);
DISPLAY INVISIBLE (-3575 4475);
FORCEPROP 1 LAST HDL_TAP TRUE
J 0
(-3250 4300);
DISPLAY 0.872340 (-3250 4300);
DISPLAY INVISIBLE (-3250 4300);
FORCEPROP 1 LAST PATH I381
J 0
(-3577 4425);
DISPLAY 0.872340 (-3577 4425);
PAINT GREEN (-3577 4425);
DISPLAY INVISIBLE (-3577 4425);
FORCEADD TAP..1
(-3375 4275);
FORCEPROP 3 LASTPIN (-3425 4275) SIG_NAME M_F_CPU0_SA_DQS_DN<4>
J 0
(-3415 4285);
DISPLAY 0.659574 (-3415 4285);
PAINT MONO (-3415 4285);
DISPLAY INVISIBLE (-3415 4285);
FORCEPROP 1 LASTPIN (-3425 4275) BN 4
J 0
(-3437 4283);
DISPLAY 0.489362 (-3437 4283);
PAINT GREEN (-3437 4283);
FORCEPROP 2 LAST CDS_LIB mstr_standard
J 0
(-3375 4275);
DISPLAY 0.723404 (-3375 4275);
PAINT MONO (-3375 4275);
DISPLAY INVISIBLE (-3375 4275);
FORCEPROP 1 LAST BODY_TYPE PLUMBING
J 0
(-3375 4325);
DISPLAY 0.872340 (-3375 4325);
PAINT GREEN (-3375 4325);
DISPLAY INVISIBLE (-3375 4325);
FORCEPROP 1 LAST HDL_TAP TRUE
J 0
(-3050 4150);
DISPLAY 0.872340 (-3050 4150);
DISPLAY INVISIBLE (-3050 4150);
FORCEPROP 1 LAST PATH I382
J 0
(-3377 4275);
DISPLAY 0.872340 (-3377 4275);
PAINT GREEN (-3377 4275);
DISPLAY INVISIBLE (-3377 4275);
FORCEADD TAP..1
(-3375 4175);
FORCEPROP 3 LASTPIN (-3425 4175) SIG_NAME M_F_CPU0_SA_DQS_DN<3>
J 0
(-3415 4185);
DISPLAY 0.659574 (-3415 4185);
PAINT MONO (-3415 4185);
DISPLAY INVISIBLE (-3415 4185);
FORCEPROP 1 LASTPIN (-3425 4175) BN 3
J 0
(-3437 4183);
DISPLAY 0.489362 (-3437 4183);
PAINT GREEN (-3437 4183);
FORCEPROP 2 LAST CDS_LIB mstr_standard
J 0
(-3375 4175);
DISPLAY 0.723404 (-3375 4175);
PAINT MONO (-3375 4175);
DISPLAY INVISIBLE (-3375 4175);
FORCEPROP 1 LAST BODY_TYPE PLUMBING
J 0
(-3375 4225);
DISPLAY 0.872340 (-3375 4225);
PAINT GREEN (-3375 4225);
DISPLAY INVISIBLE (-3375 4225);
FORCEPROP 1 LAST HDL_TAP TRUE
J 0
(-3050 4050);
DISPLAY 0.872340 (-3050 4050);
DISPLAY INVISIBLE (-3050 4050);
FORCEPROP 1 LAST PATH I383
J 0
(-3377 4175);
DISPLAY 0.872340 (-3377 4175);
PAINT GREEN (-3377 4175);
DISPLAY INVISIBLE (-3377 4175);
FORCEADD TAP..1
(-3375 4075);
FORCEPROP 3 LASTPIN (-3425 4075) SIG_NAME M_F_CPU0_SA_DQS_DN<2>
J 0
(-3415 4085);
DISPLAY 0.659574 (-3415 4085);
PAINT MONO (-3415 4085);
DISPLAY INVISIBLE (-3415 4085);
FORCEPROP 1 LASTPIN (-3425 4075) BN 2
J 0
(-3437 4083);
DISPLAY 0.489362 (-3437 4083);
PAINT GREEN (-3437 4083);
FORCEPROP 2 LAST CDS_LIB mstr_standard
J 0
(-3375 4075);
DISPLAY 0.723404 (-3375 4075);
PAINT MONO (-3375 4075);
DISPLAY INVISIBLE (-3375 4075);
FORCEPROP 1 LAST BODY_TYPE PLUMBING
J 0
(-3375 4125);
DISPLAY 0.872340 (-3375 4125);
PAINT GREEN (-3375 4125);
DISPLAY INVISIBLE (-3375 4125);
FORCEPROP 1 LAST HDL_TAP TRUE
J 0
(-3050 3950);
DISPLAY 0.872340 (-3050 3950);
DISPLAY INVISIBLE (-3050 3950);
FORCEPROP 1 LAST PATH I384
J 0
(-3377 4075);
DISPLAY 0.872340 (-3377 4075);
PAINT GREEN (-3377 4075);
DISPLAY INVISIBLE (-3377 4075);
FORCEADD TAP..1
(-3375 3975);
FORCEPROP 3 LASTPIN (-3425 3975) SIG_NAME M_F_CPU0_SA_DQS_DN<1>
J 0
(-3415 3985);
DISPLAY 0.659574 (-3415 3985);
PAINT MONO (-3415 3985);
DISPLAY INVISIBLE (-3415 3985);
FORCEPROP 1 LASTPIN (-3425 3975) BN 1
J 0
(-3437 3983);
DISPLAY 0.489362 (-3437 3983);
PAINT GREEN (-3437 3983);
FORCEPROP 2 LAST CDS_LIB mstr_standard
J 0
(-3375 3975);
DISPLAY 0.723404 (-3375 3975);
PAINT MONO (-3375 3975);
DISPLAY INVISIBLE (-3375 3975);
FORCEPROP 1 LAST BODY_TYPE PLUMBING
J 0
(-3375 4025);
DISPLAY 0.872340 (-3375 4025);
PAINT GREEN (-3375 4025);
DISPLAY INVISIBLE (-3375 4025);
FORCEPROP 1 LAST HDL_TAP TRUE
J 0
(-3050 3850);
DISPLAY 0.872340 (-3050 3850);
DISPLAY INVISIBLE (-3050 3850);
FORCEPROP 1 LAST PATH I385
J 0
(-3377 3975);
DISPLAY 0.872340 (-3377 3975);
PAINT GREEN (-3377 3975);
DISPLAY INVISIBLE (-3377 3975);
FORCEADD TAP..1
(-3375 3875);
FORCEPROP 3 LASTPIN (-3425 3875) SIG_NAME M_F_CPU0_SA_DQS_DN<0>
J 0
(-3415 3885);
DISPLAY 0.659574 (-3415 3885);
PAINT MONO (-3415 3885);
DISPLAY INVISIBLE (-3415 3885);
FORCEPROP 1 LASTPIN (-3425 3875) BN 0
J 0
(-3437 3883);
DISPLAY 0.489362 (-3437 3883);
PAINT GREEN (-3437 3883);
FORCEPROP 2 LAST CDS_LIB mstr_standard
J 0
(-3375 3875);
DISPLAY 0.723404 (-3375 3875);
PAINT MONO (-3375 3875);
DISPLAY INVISIBLE (-3375 3875);
FORCEPROP 1 LAST BODY_TYPE PLUMBING
J 0
(-3375 3925);
DISPLAY 0.872340 (-3375 3925);
PAINT GREEN (-3375 3925);
DISPLAY INVISIBLE (-3375 3925);
FORCEPROP 1 LAST HDL_TAP TRUE
J 0
(-3050 3750);
DISPLAY 0.872340 (-3050 3750);
DISPLAY INVISIBLE (-3050 3750);
FORCEPROP 1 LAST PATH I386
J 0
(-3377 3875);
DISPLAY 0.872340 (-3377 3875);
PAINT GREEN (-3377 3875);
DISPLAY INVISIBLE (-3377 3875);
FORCEADD TAP..1
(-3575 4225);
FORCEPROP 3 LASTPIN (-3625 4225) SIG_NAME M_F_CPU0_SA_DQS_DP<3>
J 0
(-3615 4235);
DISPLAY 0.659574 (-3615 4235);
PAINT MONO (-3615 4235);
DISPLAY INVISIBLE (-3615 4235);
FORCEPROP 1 LASTPIN (-3625 4225) BN 3
J 0
(-3637 4233);
DISPLAY 0.489362 (-3637 4233);
PAINT GREEN (-3637 4233);
FORCEPROP 2 LAST CDS_LIB mstr_standard
J 0
(-3575 4225);
DISPLAY 0.723404 (-3575 4225);
PAINT MONO (-3575 4225);
DISPLAY INVISIBLE (-3575 4225);
FORCEPROP 1 LAST BODY_TYPE PLUMBING
J 0
(-3575 4275);
DISPLAY 0.872340 (-3575 4275);
PAINT GREEN (-3575 4275);
DISPLAY INVISIBLE (-3575 4275);
FORCEPROP 1 LAST HDL_TAP TRUE
J 0
(-3250 4100);
DISPLAY 0.872340 (-3250 4100);
DISPLAY INVISIBLE (-3250 4100);
FORCEPROP 1 LAST PATH I387
J 0
(-3577 4225);
DISPLAY 0.872340 (-3577 4225);
PAINT GREEN (-3577 4225);
DISPLAY INVISIBLE (-3577 4225);
FORCEADD TAP..1
(-3575 4325);
FORCEPROP 3 LASTPIN (-3625 4325) SIG_NAME M_F_CPU0_SA_DQS_DP<4>
J 0
(-3615 4335);
DISPLAY 0.659574 (-3615 4335);
PAINT MONO (-3615 4335);
DISPLAY INVISIBLE (-3615 4335);
FORCEPROP 1 LASTPIN (-3625 4325) BN 4
J 0
(-3637 4333);
DISPLAY 0.489362 (-3637 4333);
PAINT GREEN (-3637 4333);
FORCEPROP 2 LAST CDS_LIB mstr_standard
J 0
(-3575 4325);
DISPLAY 0.723404 (-3575 4325);
PAINT MONO (-3575 4325);
DISPLAY INVISIBLE (-3575 4325);
FORCEPROP 1 LAST BODY_TYPE PLUMBING
J 0
(-3575 4375);
DISPLAY 0.872340 (-3575 4375);
PAINT GREEN (-3575 4375);
DISPLAY INVISIBLE (-3575 4375);
FORCEPROP 1 LAST HDL_TAP TRUE
J 0
(-3250 4200);
DISPLAY 0.872340 (-3250 4200);
DISPLAY INVISIBLE (-3250 4200);
FORCEPROP 1 LAST PATH I388
J 0
(-3577 4325);
DISPLAY 0.872340 (-3577 4325);
PAINT GREEN (-3577 4325);
DISPLAY INVISIBLE (-3577 4325);
FORCEADD TAP..1
(-3575 4125);
FORCEPROP 3 LASTPIN (-3625 4125) SIG_NAME M_F_CPU0_SA_DQS_DP<2>
J 0
(-3615 4135);
DISPLAY 0.659574 (-3615 4135);
PAINT MONO (-3615 4135);
DISPLAY INVISIBLE (-3615 4135);
FORCEPROP 1 LASTPIN (-3625 4125) BN 2
J 0
(-3637 4133);
DISPLAY 0.489362 (-3637 4133);
PAINT GREEN (-3637 4133);
FORCEPROP 2 LAST CDS_LIB mstr_standard
J 0
(-3575 4125);
DISPLAY 0.723404 (-3575 4125);
PAINT MONO (-3575 4125);
DISPLAY INVISIBLE (-3575 4125);
FORCEPROP 1 LAST BODY_TYPE PLUMBING
J 0
(-3575 4175);
DISPLAY 0.872340 (-3575 4175);
PAINT GREEN (-3575 4175);
DISPLAY INVISIBLE (-3575 4175);
FORCEPROP 1 LAST HDL_TAP TRUE
J 0
(-3250 4000);
DISPLAY 0.872340 (-3250 4000);
DISPLAY INVISIBLE (-3250 4000);
FORCEPROP 1 LAST PATH I389
J 0
(-3577 4125);
DISPLAY 0.872340 (-3577 4125);
PAINT GREEN (-3577 4125);
DISPLAY INVISIBLE (-3577 4125);
FORCEADD TAP..1
(-3575 4025);
FORCEPROP 3 LASTPIN (-3625 4025) SIG_NAME M_F_CPU0_SA_DQS_DP<1>
J 0
(-3615 4035);
DISPLAY 0.659574 (-3615 4035);
PAINT MONO (-3615 4035);
DISPLAY INVISIBLE (-3615 4035);
FORCEPROP 1 LASTPIN (-3625 4025) BN 1
J 0
(-3637 4033);
DISPLAY 0.489362 (-3637 4033);
PAINT GREEN (-3637 4033);
FORCEPROP 2 LAST CDS_LIB mstr_standard
J 0
(-3575 4025);
DISPLAY 0.723404 (-3575 4025);
PAINT MONO (-3575 4025);
DISPLAY INVISIBLE (-3575 4025);
FORCEPROP 1 LAST BODY_TYPE PLUMBING
J 0
(-3575 4075);
DISPLAY 0.872340 (-3575 4075);
PAINT GREEN (-3575 4075);
DISPLAY INVISIBLE (-3575 4075);
FORCEPROP 1 LAST HDL_TAP TRUE
J 0
(-3250 3900);
DISPLAY 0.872340 (-3250 3900);
DISPLAY INVISIBLE (-3250 3900);
FORCEPROP 1 LAST PATH I390
J 0
(-3577 4025);
DISPLAY 0.872340 (-3577 4025);
PAINT GREEN (-3577 4025);
DISPLAY INVISIBLE (-3577 4025);
FORCEADD TAP..1
(-3575 3925);
FORCEPROP 3 LASTPIN (-3625 3925) SIG_NAME M_F_CPU0_SA_DQS_DP<0>
J 0
(-3615 3935);
DISPLAY 0.659574 (-3615 3935);
PAINT MONO (-3615 3935);
DISPLAY INVISIBLE (-3615 3935);
FORCEPROP 1 LASTPIN (-3625 3925) BN 0
J 0
(-3637 3933);
DISPLAY 0.489362 (-3637 3933);
PAINT GREEN (-3637 3933);
FORCEPROP 2 LAST CDS_LIB mstr_standard
J 0
(-3575 3925);
DISPLAY 0.723404 (-3575 3925);
PAINT MONO (-3575 3925);
DISPLAY INVISIBLE (-3575 3925);
FORCEPROP 1 LAST BODY_TYPE PLUMBING
J 0
(-3575 3975);
DISPLAY 0.872340 (-3575 3975);
PAINT GREEN (-3575 3975);
DISPLAY INVISIBLE (-3575 3975);
FORCEPROP 1 LAST HDL_TAP TRUE
J 0
(-3250 3800);
DISPLAY 0.872340 (-3250 3800);
DISPLAY INVISIBLE (-3250 3800);
FORCEPROP 1 LAST PATH I391
J 0
(-3577 3925);
DISPLAY 0.872340 (-3577 3925);
PAINT GREEN (-3577 3925);
DISPLAY INVISIBLE (-3577 3925);
FORCEADD TAP..1
(-3375 3725);
FORCEPROP 3 LASTPIN (-3425 3725) SIG_NAME M_F_CPU0_SB_DQS_DN<9>
J 0
(-3415 3735);
DISPLAY 0.659574 (-3415 3735);
PAINT MONO (-3415 3735);
DISPLAY INVISIBLE (-3415 3735);
FORCEPROP 1 LASTPIN (-3425 3725) BN 9
J 0
(-3437 3733);
DISPLAY 0.489362 (-3437 3733);
PAINT GREEN (-3437 3733);
FORCEPROP 2 LAST CDS_LIB mstr_standard
J 0
(-3375 3725);
DISPLAY 0.723404 (-3375 3725);
PAINT MONO (-3375 3725);
DISPLAY INVISIBLE (-3375 3725);
FORCEPROP 1 LAST BODY_TYPE PLUMBING
J 0
(-3375 3775);
DISPLAY 0.872340 (-3375 3775);
PAINT GREEN (-3375 3775);
DISPLAY INVISIBLE (-3375 3775);
FORCEPROP 1 LAST HDL_TAP TRUE
J 0
(-3050 3600);
DISPLAY 0.872340 (-3050 3600);
DISPLAY INVISIBLE (-3050 3600);
FORCEPROP 1 LAST PATH I392
J 0
(-3377 3725);
DISPLAY 0.872340 (-3377 3725);
PAINT GREEN (-3377 3725);
DISPLAY INVISIBLE (-3377 3725);
FORCEADD TAP..1
(-3375 3625);
FORCEPROP 3 LASTPIN (-3425 3625) SIG_NAME M_F_CPU0_SB_DQS_DN<8>
J 0
(-3415 3635);
DISPLAY 0.659574 (-3415 3635);
PAINT MONO (-3415 3635);
DISPLAY INVISIBLE (-3415 3635);
FORCEPROP 1 LASTPIN (-3425 3625) BN 8
J 0
(-3437 3633);
DISPLAY 0.489362 (-3437 3633);
PAINT GREEN (-3437 3633);
FORCEPROP 2 LAST CDS_LIB mstr_standard
J 0
(-3375 3625);
DISPLAY 0.723404 (-3375 3625);
PAINT MONO (-3375 3625);
DISPLAY INVISIBLE (-3375 3625);
FORCEPROP 1 LAST BODY_TYPE PLUMBING
J 0
(-3375 3675);
DISPLAY 0.872340 (-3375 3675);
PAINT GREEN (-3375 3675);
DISPLAY INVISIBLE (-3375 3675);
FORCEPROP 1 LAST HDL_TAP TRUE
J 0
(-3050 3500);
DISPLAY 0.872340 (-3050 3500);
DISPLAY INVISIBLE (-3050 3500);
FORCEPROP 1 LAST PATH I393
J 0
(-3377 3625);
DISPLAY 0.872340 (-3377 3625);
PAINT GREEN (-3377 3625);
DISPLAY INVISIBLE (-3377 3625);
FORCEADD TAP..1
(-3375 3525);
FORCEPROP 3 LASTPIN (-3425 3525) SIG_NAME M_F_CPU0_SB_DQS_DN<7>
J 0
(-3415 3535);
DISPLAY 0.659574 (-3415 3535);
PAINT MONO (-3415 3535);
DISPLAY INVISIBLE (-3415 3535);
FORCEPROP 1 LASTPIN (-3425 3525) BN 7
J 0
(-3437 3533);
DISPLAY 0.489362 (-3437 3533);
PAINT GREEN (-3437 3533);
FORCEPROP 2 LAST CDS_LIB mstr_standard
J 0
(-3375 3525);
DISPLAY 0.723404 (-3375 3525);
PAINT MONO (-3375 3525);
DISPLAY INVISIBLE (-3375 3525);
FORCEPROP 1 LAST BODY_TYPE PLUMBING
J 0
(-3375 3575);
DISPLAY 0.872340 (-3375 3575);
PAINT GREEN (-3375 3575);
DISPLAY INVISIBLE (-3375 3575);
FORCEPROP 1 LAST HDL_TAP TRUE
J 0
(-3050 3400);
DISPLAY 0.872340 (-3050 3400);
DISPLAY INVISIBLE (-3050 3400);
FORCEPROP 1 LAST PATH I394
J 0
(-3377 3525);
DISPLAY 0.872340 (-3377 3525);
PAINT GREEN (-3377 3525);
DISPLAY INVISIBLE (-3377 3525);
FORCEADD TAP..1
(-3375 3325);
FORCEPROP 3 LASTPIN (-3425 3325) SIG_NAME M_F_CPU0_SB_DQS_DN<5>
J 0
(-3415 3335);
DISPLAY 0.659574 (-3415 3335);
PAINT MONO (-3415 3335);
DISPLAY INVISIBLE (-3415 3335);
FORCEPROP 1 LASTPIN (-3425 3325) BN 5
J 0
(-3437 3333);
DISPLAY 0.489362 (-3437 3333);
PAINT GREEN (-3437 3333);
FORCEPROP 2 LAST CDS_LIB mstr_standard
J 0
(-3375 3325);
DISPLAY 0.723404 (-3375 3325);
PAINT MONO (-3375 3325);
DISPLAY INVISIBLE (-3375 3325);
FORCEPROP 1 LAST BODY_TYPE PLUMBING
J 0
(-3375 3375);
DISPLAY 0.872340 (-3375 3375);
PAINT GREEN (-3375 3375);
DISPLAY INVISIBLE (-3375 3375);
FORCEPROP 1 LAST HDL_TAP TRUE
J 0
(-3050 3200);
DISPLAY 0.872340 (-3050 3200);
DISPLAY INVISIBLE (-3050 3200);
FORCEPROP 1 LAST PATH I395
J 0
(-3377 3325);
DISPLAY 0.872340 (-3377 3325);
PAINT GREEN (-3377 3325);
DISPLAY INVISIBLE (-3377 3325);
FORCEADD TAP..1
(-3375 3425);
FORCEPROP 3 LASTPIN (-3425 3425) SIG_NAME M_F_CPU0_SB_DQS_DN<6>
J 0
(-3415 3435);
DISPLAY 0.659574 (-3415 3435);
PAINT MONO (-3415 3435);
DISPLAY INVISIBLE (-3415 3435);
FORCEPROP 1 LASTPIN (-3425 3425) BN 6
J 0
(-3437 3433);
DISPLAY 0.489362 (-3437 3433);
PAINT GREEN (-3437 3433);
FORCEPROP 2 LAST CDS_LIB mstr_standard
J 0
(-3375 3425);
DISPLAY 0.723404 (-3375 3425);
PAINT MONO (-3375 3425);
DISPLAY INVISIBLE (-3375 3425);
FORCEPROP 1 LAST BODY_TYPE PLUMBING
J 0
(-3375 3475);
DISPLAY 0.872340 (-3375 3475);
PAINT GREEN (-3375 3475);
DISPLAY INVISIBLE (-3375 3475);
FORCEPROP 1 LAST HDL_TAP TRUE
J 0
(-3050 3300);
DISPLAY 0.872340 (-3050 3300);
DISPLAY INVISIBLE (-3050 3300);
FORCEPROP 1 LAST PATH I396
J 0
(-3377 3425);
DISPLAY 0.872340 (-3377 3425);
PAINT GREEN (-3377 3425);
DISPLAY INVISIBLE (-3377 3425);
FORCEADD TAP..1
(-3575 3675);
FORCEPROP 3 LASTPIN (-3625 3675) SIG_NAME M_F_CPU0_SB_DQS_DP<8>
J 0
(-3615 3685);
DISPLAY 0.659574 (-3615 3685);
PAINT MONO (-3615 3685);
DISPLAY INVISIBLE (-3615 3685);
FORCEPROP 1 LASTPIN (-3625 3675) BN 8
J 0
(-3637 3683);
DISPLAY 0.489362 (-3637 3683);
PAINT GREEN (-3637 3683);
FORCEPROP 2 LAST CDS_LIB mstr_standard
J 0
(-3575 3675);
DISPLAY 0.723404 (-3575 3675);
PAINT MONO (-3575 3675);
DISPLAY INVISIBLE (-3575 3675);
FORCEPROP 1 LAST BODY_TYPE PLUMBING
J 0
(-3575 3725);
DISPLAY 0.872340 (-3575 3725);
PAINT GREEN (-3575 3725);
DISPLAY INVISIBLE (-3575 3725);
FORCEPROP 1 LAST HDL_TAP TRUE
J 0
(-3250 3550);
DISPLAY 0.872340 (-3250 3550);
DISPLAY INVISIBLE (-3250 3550);
FORCEPROP 1 LAST PATH I397
J 0
(-3577 3675);
DISPLAY 0.872340 (-3577 3675);
PAINT GREEN (-3577 3675);
DISPLAY INVISIBLE (-3577 3675);
FORCEADD TAP..1
(-3575 3775);
FORCEPROP 3 LASTPIN (-3625 3775) SIG_NAME M_F_CPU0_SB_DQS_DP<9>
J 0
(-3615 3785);
DISPLAY 0.659574 (-3615 3785);
PAINT MONO (-3615 3785);
DISPLAY INVISIBLE (-3615 3785);
FORCEPROP 1 LASTPIN (-3625 3775) BN 9
J 0
(-3637 3783);
DISPLAY 0.489362 (-3637 3783);
PAINT GREEN (-3637 3783);
FORCEPROP 2 LAST CDS_LIB mstr_standard
J 0
(-3575 3775);
DISPLAY 0.723404 (-3575 3775);
PAINT MONO (-3575 3775);
DISPLAY INVISIBLE (-3575 3775);
FORCEPROP 1 LAST BODY_TYPE PLUMBING
J 0
(-3575 3825);
DISPLAY 0.872340 (-3575 3825);
PAINT GREEN (-3575 3825);
DISPLAY INVISIBLE (-3575 3825);
FORCEPROP 1 LAST HDL_TAP TRUE
J 0
(-3250 3650);
DISPLAY 0.872340 (-3250 3650);
DISPLAY INVISIBLE (-3250 3650);
FORCEPROP 1 LAST PATH I398
J 0
(-3577 3775);
DISPLAY 0.872340 (-3577 3775);
PAINT GREEN (-3577 3775);
DISPLAY INVISIBLE (-3577 3775);
FORCEADD TAP..1
(-3575 3575);
FORCEPROP 3 LASTPIN (-3625 3575) SIG_NAME M_F_CPU0_SB_DQS_DP<7>
J 0
(-3615 3585);
DISPLAY 0.659574 (-3615 3585);
PAINT MONO (-3615 3585);
DISPLAY INVISIBLE (-3615 3585);
FORCEPROP 1 LASTPIN (-3625 3575) BN 7
J 0
(-3637 3583);
DISPLAY 0.489362 (-3637 3583);
PAINT GREEN (-3637 3583);
FORCEPROP 2 LAST CDS_LIB mstr_standard
J 0
(-3575 3575);
DISPLAY 0.723404 (-3575 3575);
PAINT MONO (-3575 3575);
DISPLAY INVISIBLE (-3575 3575);
FORCEPROP 1 LAST BODY_TYPE PLUMBING
J 0
(-3575 3625);
DISPLAY 0.872340 (-3575 3625);
PAINT GREEN (-3575 3625);
DISPLAY INVISIBLE (-3575 3625);
FORCEPROP 1 LAST HDL_TAP TRUE
J 0
(-3250 3450);
DISPLAY 0.872340 (-3250 3450);
DISPLAY INVISIBLE (-3250 3450);
FORCEPROP 1 LAST PATH I399
J 0
(-3577 3575);
DISPLAY 0.872340 (-3577 3575);
PAINT GREEN (-3577 3575);
DISPLAY INVISIBLE (-3577 3575);
FORCEADD TAP..1
(-3575 3475);
FORCEPROP 3 LASTPIN (-3625 3475) SIG_NAME M_F_CPU0_SB_DQS_DP<6>
J 0
(-3615 3485);
DISPLAY 0.659574 (-3615 3485);
PAINT MONO (-3615 3485);
DISPLAY INVISIBLE (-3615 3485);
FORCEPROP 1 LASTPIN (-3625 3475) BN 6
J 0
(-3637 3483);
DISPLAY 0.489362 (-3637 3483);
PAINT GREEN (-3637 3483);
FORCEPROP 2 LAST CDS_LIB mstr_standard
J 0
(-3575 3475);
DISPLAY 0.723404 (-3575 3475);
PAINT MONO (-3575 3475);
DISPLAY INVISIBLE (-3575 3475);
FORCEPROP 1 LAST BODY_TYPE PLUMBING
J 0
(-3575 3525);
DISPLAY 0.872340 (-3575 3525);
PAINT GREEN (-3575 3525);
DISPLAY INVISIBLE (-3575 3525);
FORCEPROP 1 LAST HDL_TAP TRUE
J 0
(-3250 3350);
DISPLAY 0.872340 (-3250 3350);
DISPLAY INVISIBLE (-3250 3350);
FORCEPROP 1 LAST PATH I400
J 0
(-3577 3475);
DISPLAY 0.872340 (-3577 3475);
PAINT GREEN (-3577 3475);
DISPLAY INVISIBLE (-3577 3475);
FORCEADD TAP..1
(-3575 3375);
FORCEPROP 3 LASTPIN (-3625 3375) SIG_NAME M_F_CPU0_SB_DQS_DP<5>
J 0
(-3615 3385);
DISPLAY 0.659574 (-3615 3385);
PAINT MONO (-3615 3385);
DISPLAY INVISIBLE (-3615 3385);
FORCEPROP 1 LASTPIN (-3625 3375) BN 5
J 0
(-3637 3383);
DISPLAY 0.489362 (-3637 3383);
PAINT GREEN (-3637 3383);
FORCEPROP 2 LAST CDS_LIB mstr_standard
J 0
(-3575 3375);
DISPLAY 0.723404 (-3575 3375);
PAINT MONO (-3575 3375);
DISPLAY INVISIBLE (-3575 3375);
FORCEPROP 1 LAST BODY_TYPE PLUMBING
J 0
(-3575 3425);
DISPLAY 0.872340 (-3575 3425);
PAINT GREEN (-3575 3425);
DISPLAY INVISIBLE (-3575 3425);
FORCEPROP 1 LAST HDL_TAP TRUE
J 0
(-3250 3250);
DISPLAY 0.872340 (-3250 3250);
DISPLAY INVISIBLE (-3250 3250);
FORCEPROP 1 LAST PATH I401
J 0
(-3577 3375);
DISPLAY 0.872340 (-3577 3375);
PAINT GREEN (-3577 3375);
DISPLAY INVISIBLE (-3577 3375);
FORCEADD TAP..1
(-3375 3225);
FORCEPROP 3 LASTPIN (-3425 3225) SIG_NAME M_F_CPU0_SB_DQS_DN<4>
J 0
(-3415 3235);
DISPLAY 0.659574 (-3415 3235);
PAINT MONO (-3415 3235);
DISPLAY INVISIBLE (-3415 3235);
FORCEPROP 1 LASTPIN (-3425 3225) BN 4
J 0
(-3437 3233);
DISPLAY 0.489362 (-3437 3233);
PAINT GREEN (-3437 3233);
FORCEPROP 2 LAST CDS_LIB mstr_standard
J 0
(-3375 3225);
DISPLAY 0.723404 (-3375 3225);
PAINT MONO (-3375 3225);
DISPLAY INVISIBLE (-3375 3225);
FORCEPROP 1 LAST BODY_TYPE PLUMBING
J 0
(-3375 3275);
DISPLAY 0.872340 (-3375 3275);
PAINT GREEN (-3375 3275);
DISPLAY INVISIBLE (-3375 3275);
FORCEPROP 1 LAST HDL_TAP TRUE
J 0
(-3050 3100);
DISPLAY 0.872340 (-3050 3100);
DISPLAY INVISIBLE (-3050 3100);
FORCEPROP 1 LAST PATH I402
J 0
(-3377 3225);
DISPLAY 0.872340 (-3377 3225);
PAINT GREEN (-3377 3225);
DISPLAY INVISIBLE (-3377 3225);
FORCEADD TAP..1
(-3375 3125);
FORCEPROP 3 LASTPIN (-3425 3125) SIG_NAME M_F_CPU0_SB_DQS_DN<3>
J 0
(-3415 3135);
DISPLAY 0.659574 (-3415 3135);
PAINT MONO (-3415 3135);
DISPLAY INVISIBLE (-3415 3135);
FORCEPROP 1 LASTPIN (-3425 3125) BN 3
J 0
(-3437 3133);
DISPLAY 0.489362 (-3437 3133);
PAINT GREEN (-3437 3133);
FORCEPROP 2 LAST CDS_LIB mstr_standard
J 0
(-3375 3125);
DISPLAY 0.723404 (-3375 3125);
PAINT MONO (-3375 3125);
DISPLAY INVISIBLE (-3375 3125);
FORCEPROP 1 LAST BODY_TYPE PLUMBING
J 0
(-3375 3175);
DISPLAY 0.872340 (-3375 3175);
PAINT GREEN (-3375 3175);
DISPLAY INVISIBLE (-3375 3175);
FORCEPROP 1 LAST HDL_TAP TRUE
J 0
(-3050 3000);
DISPLAY 0.872340 (-3050 3000);
DISPLAY INVISIBLE (-3050 3000);
FORCEPROP 1 LAST PATH I403
J 0
(-3377 3125);
DISPLAY 0.872340 (-3377 3125);
PAINT GREEN (-3377 3125);
DISPLAY INVISIBLE (-3377 3125);
FORCEADD TAP..1
(-3375 3025);
FORCEPROP 3 LASTPIN (-3425 3025) SIG_NAME M_F_CPU0_SB_DQS_DN<2>
J 0
(-3415 3035);
DISPLAY 0.659574 (-3415 3035);
PAINT MONO (-3415 3035);
DISPLAY INVISIBLE (-3415 3035);
FORCEPROP 1 LASTPIN (-3425 3025) BN 2
J 0
(-3437 3033);
DISPLAY 0.489362 (-3437 3033);
PAINT GREEN (-3437 3033);
FORCEPROP 2 LAST CDS_LIB mstr_standard
J 0
(-3375 3025);
DISPLAY 0.723404 (-3375 3025);
PAINT MONO (-3375 3025);
DISPLAY INVISIBLE (-3375 3025);
FORCEPROP 1 LAST BODY_TYPE PLUMBING
J 0
(-3375 3075);
DISPLAY 0.872340 (-3375 3075);
PAINT GREEN (-3375 3075);
DISPLAY INVISIBLE (-3375 3075);
FORCEPROP 1 LAST HDL_TAP TRUE
J 0
(-3050 2900);
DISPLAY 0.872340 (-3050 2900);
DISPLAY INVISIBLE (-3050 2900);
FORCEPROP 1 LAST PATH I404
J 0
(-3377 3025);
DISPLAY 0.872340 (-3377 3025);
PAINT GREEN (-3377 3025);
DISPLAY INVISIBLE (-3377 3025);
FORCEADD TAP..1
(-3375 2825);
FORCEPROP 3 LASTPIN (-3425 2825) SIG_NAME M_F_CPU0_SB_DQS_DN<0>
J 0
(-3415 2835);
DISPLAY 0.659574 (-3415 2835);
PAINT MONO (-3415 2835);
DISPLAY INVISIBLE (-3415 2835);
FORCEPROP 1 LASTPIN (-3425 2825) BN 0
J 0
(-3437 2833);
DISPLAY 0.489362 (-3437 2833);
PAINT GREEN (-3437 2833);
FORCEPROP 2 LAST CDS_LIB mstr_standard
J 0
(-3375 2825);
DISPLAY 0.723404 (-3375 2825);
PAINT MONO (-3375 2825);
DISPLAY INVISIBLE (-3375 2825);
FORCEPROP 1 LAST BODY_TYPE PLUMBING
J 0
(-3375 2875);
DISPLAY 0.872340 (-3375 2875);
PAINT GREEN (-3375 2875);
DISPLAY INVISIBLE (-3375 2875);
FORCEPROP 1 LAST HDL_TAP TRUE
J 0
(-3050 2700);
DISPLAY 0.872340 (-3050 2700);
DISPLAY INVISIBLE (-3050 2700);
FORCEPROP 1 LAST PATH I405
J 0
(-3377 2825);
DISPLAY 0.872340 (-3377 2825);
PAINT GREEN (-3377 2825);
DISPLAY INVISIBLE (-3377 2825);
FORCEADD TAP..1
(-3375 2925);
FORCEPROP 3 LASTPIN (-3425 2925) SIG_NAME M_F_CPU0_SB_DQS_DN<1>
J 0
(-3415 2935);
DISPLAY 0.659574 (-3415 2935);
PAINT MONO (-3415 2935);
DISPLAY INVISIBLE (-3415 2935);
FORCEPROP 1 LASTPIN (-3425 2925) BN 1
J 0
(-3437 2933);
DISPLAY 0.489362 (-3437 2933);
PAINT GREEN (-3437 2933);
FORCEPROP 2 LAST CDS_LIB mstr_standard
J 0
(-3375 2925);
DISPLAY 0.723404 (-3375 2925);
PAINT MONO (-3375 2925);
DISPLAY INVISIBLE (-3375 2925);
FORCEPROP 1 LAST BODY_TYPE PLUMBING
J 0
(-3375 2975);
DISPLAY 0.872340 (-3375 2975);
PAINT GREEN (-3375 2975);
DISPLAY INVISIBLE (-3375 2975);
FORCEPROP 1 LAST HDL_TAP TRUE
J 0
(-3050 2800);
DISPLAY 0.872340 (-3050 2800);
DISPLAY INVISIBLE (-3050 2800);
FORCEPROP 1 LAST PATH I406
J 0
(-3377 2925);
DISPLAY 0.872340 (-3377 2925);
PAINT GREEN (-3377 2925);
DISPLAY INVISIBLE (-3377 2925);
FORCEADD TAP..1
(-3575 3175);
FORCEPROP 3 LASTPIN (-3625 3175) SIG_NAME M_F_CPU0_SB_DQS_DP<3>
J 0
(-3615 3185);
DISPLAY 0.659574 (-3615 3185);
PAINT MONO (-3615 3185);
DISPLAY INVISIBLE (-3615 3185);
FORCEPROP 1 LASTPIN (-3625 3175) BN 3
J 0
(-3637 3183);
DISPLAY 0.489362 (-3637 3183);
PAINT GREEN (-3637 3183);
FORCEPROP 2 LAST CDS_LIB mstr_standard
J 0
(-3575 3175);
DISPLAY 0.723404 (-3575 3175);
PAINT MONO (-3575 3175);
DISPLAY INVISIBLE (-3575 3175);
FORCEPROP 1 LAST BODY_TYPE PLUMBING
J 0
(-3575 3225);
DISPLAY 0.872340 (-3575 3225);
PAINT GREEN (-3575 3225);
DISPLAY INVISIBLE (-3575 3225);
FORCEPROP 1 LAST HDL_TAP TRUE
J 0
(-3250 3050);
DISPLAY 0.872340 (-3250 3050);
DISPLAY INVISIBLE (-3250 3050);
FORCEPROP 1 LAST PATH I407
J 0
(-3577 3175);
DISPLAY 0.872340 (-3577 3175);
PAINT GREEN (-3577 3175);
DISPLAY INVISIBLE (-3577 3175);
FORCEADD TAP..1
(-3575 3275);
FORCEPROP 3 LASTPIN (-3625 3275) SIG_NAME M_F_CPU0_SB_DQS_DP<4>
J 0
(-3615 3285);
DISPLAY 0.659574 (-3615 3285);
PAINT MONO (-3615 3285);
DISPLAY INVISIBLE (-3615 3285);
FORCEPROP 1 LASTPIN (-3625 3275) BN 4
J 0
(-3637 3283);
DISPLAY 0.489362 (-3637 3283);
PAINT GREEN (-3637 3283);
FORCEPROP 2 LAST CDS_LIB mstr_standard
J 0
(-3575 3275);
DISPLAY 0.723404 (-3575 3275);
PAINT MONO (-3575 3275);
DISPLAY INVISIBLE (-3575 3275);
FORCEPROP 1 LAST BODY_TYPE PLUMBING
J 0
(-3575 3325);
DISPLAY 0.872340 (-3575 3325);
PAINT GREEN (-3575 3325);
DISPLAY INVISIBLE (-3575 3325);
FORCEPROP 1 LAST HDL_TAP TRUE
J 0
(-3250 3150);
DISPLAY 0.872340 (-3250 3150);
DISPLAY INVISIBLE (-3250 3150);
FORCEPROP 1 LAST PATH I408
J 0
(-3577 3275);
DISPLAY 0.872340 (-3577 3275);
PAINT GREEN (-3577 3275);
DISPLAY INVISIBLE (-3577 3275);
FORCEADD TAP..1
(-3575 3075);
FORCEPROP 3 LASTPIN (-3625 3075) SIG_NAME M_F_CPU0_SB_DQS_DP<2>
J 0
(-3615 3085);
DISPLAY 0.659574 (-3615 3085);
PAINT MONO (-3615 3085);
DISPLAY INVISIBLE (-3615 3085);
FORCEPROP 1 LASTPIN (-3625 3075) BN 2
J 0
(-3637 3083);
DISPLAY 0.489362 (-3637 3083);
PAINT GREEN (-3637 3083);
FORCEPROP 2 LAST CDS_LIB mstr_standard
J 0
(-3575 3075);
DISPLAY 0.723404 (-3575 3075);
PAINT MONO (-3575 3075);
DISPLAY INVISIBLE (-3575 3075);
FORCEPROP 1 LAST BODY_TYPE PLUMBING
J 0
(-3575 3125);
DISPLAY 0.872340 (-3575 3125);
PAINT GREEN (-3575 3125);
DISPLAY INVISIBLE (-3575 3125);
FORCEPROP 1 LAST HDL_TAP TRUE
J 0
(-3250 2950);
DISPLAY 0.872340 (-3250 2950);
DISPLAY INVISIBLE (-3250 2950);
FORCEPROP 1 LAST PATH I409
J 0
(-3577 3075);
DISPLAY 0.872340 (-3577 3075);
PAINT GREEN (-3577 3075);
DISPLAY INVISIBLE (-3577 3075);
FORCEADD TAP..1
(-3575 2975);
FORCEPROP 3 LASTPIN (-3625 2975) SIG_NAME M_F_CPU0_SB_DQS_DP<1>
J 0
(-3615 2985);
DISPLAY 0.659574 (-3615 2985);
PAINT MONO (-3615 2985);
DISPLAY INVISIBLE (-3615 2985);
FORCEPROP 1 LASTPIN (-3625 2975) BN 1
J 0
(-3637 2983);
DISPLAY 0.489362 (-3637 2983);
PAINT GREEN (-3637 2983);
FORCEPROP 2 LAST CDS_LIB mstr_standard
J 0
(-3575 2975);
DISPLAY 0.723404 (-3575 2975);
PAINT MONO (-3575 2975);
DISPLAY INVISIBLE (-3575 2975);
FORCEPROP 1 LAST BODY_TYPE PLUMBING
J 0
(-3575 3025);
DISPLAY 0.872340 (-3575 3025);
PAINT GREEN (-3575 3025);
DISPLAY INVISIBLE (-3575 3025);
FORCEPROP 1 LAST HDL_TAP TRUE
J 0
(-3250 2850);
DISPLAY 0.872340 (-3250 2850);
DISPLAY INVISIBLE (-3250 2850);
FORCEPROP 1 LAST PATH I410
J 0
(-3577 2975);
DISPLAY 0.872340 (-3577 2975);
PAINT GREEN (-3577 2975);
DISPLAY INVISIBLE (-3577 2975);
FORCEADD TAP..1
(-3575 2875);
FORCEPROP 3 LASTPIN (-3625 2875) SIG_NAME M_F_CPU0_SB_DQS_DP<0>
J 0
(-3615 2885);
DISPLAY 0.659574 (-3615 2885);
PAINT MONO (-3615 2885);
DISPLAY INVISIBLE (-3615 2885);
FORCEPROP 1 LASTPIN (-3625 2875) BN 0
J 0
(-3637 2883);
DISPLAY 0.489362 (-3637 2883);
PAINT GREEN (-3637 2883);
FORCEPROP 2 LAST CDS_LIB mstr_standard
J 0
(-3575 2875);
DISPLAY 0.723404 (-3575 2875);
PAINT MONO (-3575 2875);
DISPLAY INVISIBLE (-3575 2875);
FORCEPROP 1 LAST BODY_TYPE PLUMBING
J 0
(-3575 2925);
DISPLAY 0.872340 (-3575 2925);
PAINT GREEN (-3575 2925);
DISPLAY INVISIBLE (-3575 2925);
FORCEPROP 1 LAST HDL_TAP TRUE
J 0
(-3250 2750);
DISPLAY 0.872340 (-3250 2750);
DISPLAY INVISIBLE (-3250 2750);
FORCEPROP 1 LAST PATH I411
J 0
(-3577 2875);
DISPLAY 0.872340 (-3577 2875);
PAINT GREEN (-3577 2875);
DISPLAY INVISIBLE (-3577 2875);
FORCEADD SCONN288_DDR506112002KQ..2
(-4525 3825);
FORCEPROP 1 LAST LOCATION J23
J 0
(-5125 5150);
DISPLAY 0.468085 (-5125 5150);
PAINT SKYBLUE (-5125 5150);
FORCEPROP 0 LAST $SEC 2
J 0
(-4975 5300);
DISPLAY 0.680851 (-4975 5300);
PAINT MONO (-4975 5300);
DISPLAY INVISIBLE (-4975 5300);
FORCEPROP 0 LAST CDS_SEC 2
J 0
(-4975 5300);
DISPLAY 1.021277 (-4975 5300);
DISPLAY INVISIBLE (-4975 5300);
FORCEPROP 0 LASTPIN (-3775 3875) $PN 12
J 0
(-3765 3885);
DISPLAY 0.680851 (-3765 3885);
PAINT MONO (-3765 3885);
FORCEPROP 0 LASTPIN (-3775 3925) $PN 11
J 0
(-3765 3935);
DISPLAY 0.680851 (-3765 3935);
PAINT MONO (-3765 3935);
FORCEPROP 0 LASTPIN (-3775 2825) $PN 105
J 0
(-3765 2835);
DISPLAY 0.680851 (-3765 2835);
PAINT MONO (-3765 2835);
FORCEPROP 0 LASTPIN (-3775 2875) $PN 104
J 0
(-3765 2885);
DISPLAY 0.680851 (-3765 2885);
PAINT MONO (-3765 2885);
FORCEPROP 0 LASTPIN (-3775 3975) $PN 23
J 0
(-3765 3985);
DISPLAY 0.680851 (-3765 3985);
PAINT MONO (-3765 3985);
FORCEPROP 0 LASTPIN (-3775 4025) $PN 22
J 0
(-3765 4035);
DISPLAY 0.680851 (-3765 4035);
PAINT MONO (-3765 4035);
FORCEPROP 0 LASTPIN (-3775 2925) $PN 116
J 0
(-3765 2935);
DISPLAY 0.680851 (-3765 2935);
PAINT MONO (-3765 2935);
FORCEPROP 0 LASTPIN (-3775 2975) $PN 115
J 0
(-3765 2985);
DISPLAY 0.680851 (-3765 2985);
PAINT MONO (-3765 2985);
FORCEPROP 0 LASTPIN (-3775 4075) $PN 34
J 0
(-3765 4085);
DISPLAY 0.680851 (-3765 4085);
PAINT MONO (-3765 4085);
FORCEPROP 0 LASTPIN (-3775 4125) $PN 33
J 0
(-3765 4135);
DISPLAY 0.680851 (-3765 4135);
PAINT MONO (-3765 4135);
FORCEPROP 0 LASTPIN (-3775 3025) $PN 127
J 0
(-3765 3035);
DISPLAY 0.680851 (-3765 3035);
PAINT MONO (-3765 3035);
FORCEPROP 0 LASTPIN (-3775 3075) $PN 126
J 0
(-3765 3085);
DISPLAY 0.680851 (-3765 3085);
PAINT MONO (-3765 3085);
FORCEPROP 0 LASTPIN (-3775 4175) $PN 45
J 0
(-3765 4185);
DISPLAY 0.680851 (-3765 4185);
PAINT MONO (-3765 4185);
FORCEPROP 0 LASTPIN (-3775 4225) $PN 44
J 0
(-3765 4235);
DISPLAY 0.680851 (-3765 4235);
PAINT MONO (-3765 4235);
FORCEPROP 0 LASTPIN (-3775 3125) $PN 138
J 0
(-3765 3135);
DISPLAY 0.680851 (-3765 3135);
PAINT MONO (-3765 3135);
FORCEPROP 0 LASTPIN (-3775 3175) $PN 137
J 0
(-3765 3185);
DISPLAY 0.680851 (-3765 3185);
PAINT MONO (-3765 3185);
FORCEPROP 0 LASTPIN (-3775 4275) $PN 56
J 0
(-3765 4285);
DISPLAY 0.680851 (-3765 4285);
PAINT MONO (-3765 4285);
FORCEPROP 0 LASTPIN (-3775 4325) $PN 55
J 0
(-3765 4335);
DISPLAY 0.680851 (-3765 4335);
PAINT MONO (-3765 4335);
FORCEPROP 0 LASTPIN (-3775 3225) $PN 238
J 0
(-3765 3235);
DISPLAY 0.680851 (-3765 3235);
PAINT MONO (-3765 3235);
FORCEPROP 0 LASTPIN (-3775 3275) $PN 239
J 0
(-3765 3285);
DISPLAY 0.680851 (-3765 3285);
PAINT MONO (-3765 3285);
FORCEPROP 0 LASTPIN (-3775 4375) $PN 156
J 0
(-3765 4385);
DISPLAY 0.680851 (-3765 4385);
PAINT MONO (-3765 4385);
FORCEPROP 0 LASTPIN (-3775 4425) $PN 157
J 0
(-3765 4435);
DISPLAY 0.680851 (-3765 4435);
PAINT MONO (-3765 4435);
FORCEPROP 0 LASTPIN (-3775 3325) $PN 249
J 0
(-3765 3335);
DISPLAY 0.680851 (-3765 3335);
PAINT MONO (-3765 3335);
FORCEPROP 0 LASTPIN (-3775 3375) $PN 250
J 0
(-3765 3385);
DISPLAY 0.680851 (-3765 3385);
PAINT MONO (-3765 3385);
FORCEPROP 0 LASTPIN (-3775 4475) $PN 167
J 0
(-3765 4485);
DISPLAY 0.680851 (-3765 4485);
PAINT MONO (-3765 4485);
FORCEPROP 0 LASTPIN (-3775 4525) $PN 168
J 0
(-3765 4535);
DISPLAY 0.680851 (-3765 4535);
PAINT MONO (-3765 4535);
FORCEPROP 0 LASTPIN (-3775 3425) $PN 260
J 0
(-3765 3435);
DISPLAY 0.680851 (-3765 3435);
PAINT MONO (-3765 3435);
FORCEPROP 0 LASTPIN (-3775 3475) $PN 261
J 0
(-3765 3485);
DISPLAY 0.680851 (-3765 3485);
PAINT MONO (-3765 3485);
FORCEPROP 0 LASTPIN (-3775 4575) $PN 178
J 0
(-3765 4585);
DISPLAY 0.680851 (-3765 4585);
PAINT MONO (-3765 4585);
FORCEPROP 0 LASTPIN (-3775 4625) $PN 179
J 0
(-3765 4635);
DISPLAY 0.680851 (-3765 4635);
PAINT MONO (-3765 4635);
FORCEPROP 0 LASTPIN (-3775 3525) $PN 271
J 0
(-3765 3535);
DISPLAY 0.680851 (-3765 3535);
PAINT MONO (-3765 3535);
FORCEPROP 0 LASTPIN (-3775 3575) $PN 272
J 0
(-3765 3585);
DISPLAY 0.680851 (-3765 3585);
PAINT MONO (-3765 3585);
FORCEPROP 0 LASTPIN (-3775 4675) $PN 189
J 0
(-3765 4685);
DISPLAY 0.680851 (-3765 4685);
PAINT MONO (-3765 4685);
FORCEPROP 0 LASTPIN (-3775 4725) $PN 190
J 0
(-3765 4735);
DISPLAY 0.680851 (-3765 4735);
PAINT MONO (-3765 4735);
FORCEPROP 0 LASTPIN (-3775 3625) $PN 282
J 0
(-3765 3635);
DISPLAY 0.680851 (-3765 3635);
PAINT MONO (-3765 3635);
FORCEPROP 0 LASTPIN (-3775 3675) $PN 283
J 0
(-3765 3685);
DISPLAY 0.680851 (-3765 3685);
PAINT MONO (-3765 3685);
FORCEPROP 0 LASTPIN (-3775 4775) $PN 200
J 0
(-3765 4785);
DISPLAY 0.680851 (-3765 4785);
PAINT MONO (-3765 4785);
FORCEPROP 0 LASTPIN (-3775 4825) $PN 201
J 0
(-3765 4835);
DISPLAY 0.680851 (-3765 4835);
PAINT MONO (-3765 4835);
FORCEPROP 0 LASTPIN (-3775 3725) $PN 94
J 0
(-3765 3735);
DISPLAY 0.680851 (-3765 3735);
PAINT MONO (-3765 3735);
FORCEPROP 0 LASTPIN (-3775 3775) $PN 93
J 0
(-3765 3785);
DISPLAY 0.680851 (-3765 3785);
PAINT MONO (-3765 3785);
FORCEPROP 2 LAST PART_TYPE SMLF
J 0
(-4975 5250);
DISPLAY 1.021277 (-4975 5250);
FORCEPROP 2 LAST VALUE SCONN288_DDR506112002KQ
J 0
(-4975 5200);
DISPLAY 0.489362 (-4975 5200);
PAINT SKYBLUE (-4975 5200);
FORCEPROP 1 LAST MATERIAL IO
J 0
(-5125 5000);
DISPLAY 0.468085 (-5125 5000);
PAINT SKYBLUE (-5125 5000);
FORCEPROP 2 LAST CDS_LIB pure_quanta
J 0
(-4525 3825);
DISPLAY INVISIBLE (-4525 3825);
FORCEPROP 1 LAST NEEDS_NO_SIZE TRUE
J 0
(-4525 3825);
DISPLAY 0.723404 (-4525 3825);
PAINT GREEN (-4525 3825);
DISPLAY INVISIBLE (-4525 3825);
FORCEPROP 1 LAST CDS_LMAN_SYM_OUTLINE -600,1150,600,-1150
J 0
(-4525 3825);
DISPLAY 0.468085 (-4525 3825);
PAINT GREEN (-4525 3825);
DISPLAY INVISIBLE (-4525 3825);
FORCEPROP 1 LAST PATH I412
J 0
(-4525 3825);
DISPLAY 0.723404 (-4525 3825);
PAINT GREEN (-4525 3825);
DISPLAY INVISIBLE (-4525 3825);
FORCEPROP 1 LAST PART_NUMBER DFHST8FS479
J 0
(-5125 5075);
DISPLAY 0.468085 (-5125 5075);
PAINT SKYBLUE (-5125 5075);
DISPLAY INVISIBLE (-5125 5075);
FORCEADD GND..1
(-2925 5800);
FORCEPROP 3 LASTPIN (-2925 5850) SIG_NAME GND\g
J 0
(-2915 5860);
DISPLAY 0.659574 (-2915 5860);
PAINT MONO (-2915 5860);
DISPLAY INVISIBLE (-2915 5860);
FORCEPROP 2 LAST ROOM MEM_EFGH_DECOUPLING_CAPS
J 0
(-2900 5875);
DISPLAY 0.659574 (-2900 5875);
PAINT RED (-2900 5875);
DISPLAY INVISIBLE (-2900 5875);
FORCEPROP 2 LAST CDS_LIB pure_quanta_power
J 0
(-2925 5800);
DISPLAY INVISIBLE (-2925 5800);
FORCEPROP 2 LAST BOM_COST MEM
J 0
(-2900 5925);
DISPLAY 0.659574 (-2900 5925);
DISPLAY INVISIBLE (-2900 5925);
FORCEPROP 1 LAST SIZE 1B
J 0
(-2850 5750);
DISPLAY 0.723404 (-2850 5750);
PAINT GREEN (-2850 5750);
DISPLAY INVISIBLE (-2850 5750);
FORCEPROP 1 LAST HDL_POWER GND
J 0
(-2925 5950);
DISPLAY 0.723404 (-2925 5950);
PAINT GREEN (-2925 5950);
DISPLAY INVISIBLE (-2925 5950);
FORCEPROP 1 LAST PATH I413
J 0
(-2850 5800);
DISPLAY 0.872340 (-2850 5800);
PAINT AQUA (-2850 5800);
DISPLAY INVISIBLE (-2850 5800);
FORCEADD Q_CAP..1
R 2
(-2925 6150);
FORCEPROP 1 LAST LOCATION C154
J 2
(-2975 6250);
DISPLAY 0.489362 (-2975 6250);
PAINT SKYBLUE (-2975 6250);
FORCEPROP 0 LAST $SEC 1
J 0
(-2975 6300);
DISPLAY 0.680851 (-2975 6300);
PAINT MONO (-2975 6300);
DISPLAY INVISIBLE (-2975 6300);
FORCEPROP 0 LAST CDS_SEC 1
J 0
(-2975 6300);
DISPLAY 0.680851 (-2975 6300);
DISPLAY INVISIBLE (-2975 6300);
FORCEPROP 1 LASTPIN (-2925 6250) $PN 1
J 2
(-2935 6230);
DISPLAY 0.489362 (-2935 6230);
PAINT MONO (-2935 6230);
FORCEPROP 1 LASTPIN (-2925 6050) $PN 2
J 2
(-2935 6030);
DISPLAY 0.489362 (-2935 6030);
PAINT MONO (-2935 6030);
FORCEPROP 1 LAST MATERIAL X6S
J 2
(-2975 6050);
DISPLAY 0.489362 (-2975 6050);
PAINT SKYBLUE (-2975 6050);
FORCEPROP 1 LAST VALUE 10UF
J 2
(-2975 6200);
DISPLAY 0.489362 (-2975 6200);
PAINT SKYBLUE (-2975 6200);
FORCEPROP 1 LAST PACK_TYPE C0805
J 2
(-2975 5950);
DISPLAY 0.489362 (-2975 5950);
PAINT SKYBLUE (-2975 5950);
FORCEPROP 1 LAST TOLERANCE 10%
J 2
(-2975 6100);
DISPLAY 0.489362 (-2975 6100);
PAINT SKYBLUE (-2975 6100);
FORCEPROP 1 LAST VOLTAGE 25V
J 2
(-2975 6150);
DISPLAY 0.489362 (-2975 6150);
PAINT SKYBLUE (-2975 6150);
FORCEPROP 2 LAST CDS_LIB pure_quanta
J 0
(-2925 6150);
DISPLAY INVISIBLE (-2925 6150);
FORCEPROP 0 LAST BOM_COST MEM
J 2
(-2980 6295);
DISPLAY 0.595745 (-2980 6295);
PAINT MONO (-2980 6295);
DISPLAY INVISIBLE (-2980 6295);
FORCEPROP 2 LAST ROOM 
J 2
(-2980 6295);
DISPLAY 0.595745 (-2980 6295);
PAINT RED (-2980 6295);
DISPLAY INVISIBLE (-2980 6295);
FORCEPROP 1 LAST PATH I414
J 2
(-2975 6300);
DISPLAY 0.978723 (-2975 6300);
PAINT WHITE (-2975 6300);
DISPLAY INVISIBLE (-2975 6300);
FORCEPROP 1 LAST PART_NUMBER CH6104KEA00
J 2
(-2975 6000);
DISPLAY 0.489362 (-2975 6000);
PAINT SKYBLUE (-2975 6000);
DISPLAY INVISIBLE (-2975 6000);
FORCEADD Q_CAP..1
R 2
(-2350 6150);
FORCEPROP 1 LAST LOCATION C155
J 2
(-2400 6250);
DISPLAY 0.489362 (-2400 6250);
PAINT SKYBLUE (-2400 6250);
FORCEPROP 0 LAST $SEC 1
J 0
(-2400 6300);
DISPLAY 0.680851 (-2400 6300);
PAINT MONO (-2400 6300);
DISPLAY INVISIBLE (-2400 6300);
FORCEPROP 0 LAST CDS_SEC 1
J 0
(-2400 6300);
DISPLAY 0.680851 (-2400 6300);
DISPLAY INVISIBLE (-2400 6300);
FORCEPROP 1 LASTPIN (-2350 6250) $PN 1
J 2
(-2360 6230);
DISPLAY 0.489362 (-2360 6230);
PAINT MONO (-2360 6230);
FORCEPROP 1 LASTPIN (-2350 6050) $PN 2
J 2
(-2360 6030);
DISPLAY 0.489362 (-2360 6030);
PAINT MONO (-2360 6030);
FORCEPROP 1 LAST MATERIAL X6S
J 2
(-2400 6050);
DISPLAY 0.489362 (-2400 6050);
PAINT SKYBLUE (-2400 6050);
FORCEPROP 1 LAST TOLERANCE 10%
J 2
(-2400 6100);
DISPLAY 0.489362 (-2400 6100);
PAINT SKYBLUE (-2400 6100);
FORCEPROP 1 LAST VALUE 10UF
J 2
(-2400 6200);
DISPLAY 0.489362 (-2400 6200);
PAINT SKYBLUE (-2400 6200);
FORCEPROP 1 LAST PACK_TYPE C0805
J 2
(-2400 5950);
DISPLAY 0.489362 (-2400 5950);
PAINT SKYBLUE (-2400 5950);
FORCEPROP 1 LAST VOLTAGE 25V
J 2
(-2400 6150);
DISPLAY 0.489362 (-2400 6150);
PAINT SKYBLUE (-2400 6150);
FORCEPROP 2 LAST CDS_LIB pure_quanta
J 0
(-2350 6150);
DISPLAY INVISIBLE (-2350 6150);
FORCEPROP 0 LAST BOM_COST MEM
J 2
(-2405 6295);
DISPLAY 0.595745 (-2405 6295);
PAINT MONO (-2405 6295);
DISPLAY INVISIBLE (-2405 6295);
FORCEPROP 2 LAST ROOM 
J 2
(-2405 6295);
DISPLAY 0.595745 (-2405 6295);
PAINT RED (-2405 6295);
DISPLAY INVISIBLE (-2405 6295);
FORCEPROP 1 LAST PATH I415
J 2
(-2400 6300);
DISPLAY 0.978723 (-2400 6300);
PAINT WHITE (-2400 6300);
DISPLAY INVISIBLE (-2400 6300);
FORCEPROP 1 LAST PART_NUMBER CH6104KEA00
J 2
(-2400 6000);
DISPLAY 0.489362 (-2400 6000);
PAINT SKYBLUE (-2400 6000);
DISPLAY INVISIBLE (-2400 6000);
FORCEADD UNIVERSAL_POWER..1
(-2925 6475);
FORCEPROP 3 LASTPIN (-2925 6425) SIG_NAME P12V_MEM_CPU0\g
J 0
(-2915 6435);
DISPLAY 0.659574 (-2915 6435);
PAINT MONO (-2915 6435);
DISPLAY INVISIBLE (-2915 6435);
FORCEPROP 1 LAST HDL_POWER P12V_MEM_CPU0
J 1
(-2950 6525);
DISPLAY 0.489362 (-2950 6525);
PAINT GREEN (-2950 6525);
FORCEPROP 2 LAST CDS_LIB pure_quanta_power
J 0
(-2925 6475);
DISPLAY INVISIBLE (-2925 6475);
FORCEPROP 2 LAST BOM_COST VR_SYSTEM
J 0
(-2925 6575);
DISPLAY 0.617021 (-2925 6575);
PAINT PURPLE (-2925 6575);
DISPLAY INVISIBLE (-2925 6575);
FORCEPROP 1 LAST PATH I416
J 0
(-2875 6500);
DISPLAY 0.872340 (-2875 6500);
PAINT AQUA (-2875 6500);
DISPLAY INVISIBLE (-2875 6500);
FORCEADD OFFPAGE..1
(-8450 2975);
FORCEPROP 2 LAST $XR5 90 
J 0
(-9152 2975);
DISPLAY 0.638298 (-9152 2975);
PAINT MONO (-9152 2975);
FORCEPROP 2 LAST $XR4 89 
J 0
(-9062 2975);
DISPLAY 0.638298 (-9062 2975);
PAINT MONO (-9062 2975);
FORCEPROP 2 LAST $XR3 88 
J 0
(-8972 2975);
DISPLAY 0.638298 (-8972 2975);
PAINT MONO (-8972 2975);
FORCEPROP 2 LAST $XR2 87 
J 0
(-8882 2975);
DISPLAY 0.638298 (-8882 2975);
PAINT MONO (-8882 2975);
FORCEPROP 2 LAST $XR1 86 
J 0
(-8792 2975);
DISPLAY 0.638298 (-8792 2975);
PAINT MONO (-8792 2975);
FORCEPROP 2 LAST $XR0 159 
J 0
(-8702 2975);
DISPLAY 0.638298 (-8702 2975);
PAINT MONO (-8702 2975);
FORCEPROP 2 LAST CDS_LIB mstr_standard
J 0
(-8450 2975);
DISPLAY 0.808511 (-8450 2975);
DISPLAY INVISIBLE (-8450 2975);
FORCEPROP 1 LAST OFFPAGE TRUE
J 0
(-8125 2850);
DISPLAY 0.872340 (-8125 2850);
PAINT GREEN (-8125 2850);
DISPLAY INVISIBLE (-8125 2850);
FORCEPROP 1 LAST COMMENT_BODY TRUE
J 0
(-8325 2875);
DISPLAY 0.872340 (-8325 2875);
PAINT GREEN (-8325 2875);
DISPLAY INVISIBLE (-8325 2875);
FORCEPROP 2 LAST PATH I417
J 0
(-8725 3025);
DISPLAY 0.680851 (-8725 3025);
DISPLAY INVISIBLE (-8725 3025);
FORCEADD Q_RES..1
(-7825 2975);
FORCEPROP 1 LAST LOCATION R1573
J 0
(-7875 3000);
DISPLAY 0.510638 (-7875 3000);
PAINT SKYBLUE (-7875 3000);
FORCEPROP 0 LAST $SEC 1
J 0
(-7875 3075);
DISPLAY 0.680851 (-7875 3075);
PAINT MONO (-7875 3075);
DISPLAY INVISIBLE (-7875 3075);
FORCEPROP 0 LAST CDS_SEC 1
J 0
(-7875 3075);
DISPLAY 0.680851 (-7875 3075);
DISPLAY INVISIBLE (-7875 3075);
FORCEPROP 1 LASTPIN (-7925 2975) $PN 1
J 0
(-7913 2987);
DISPLAY 0.787234 (-7913 2987);
PAINT MONO (-7913 2987);
FORCEPROP 1 LASTPIN (-7725 2975) $PN 2
J 0
(-7763 2987);
DISPLAY 0.787234 (-7763 2987);
PAINT MONO (-7763 2987);
FORCEPROP 1 LAST VALUE 49.9
J 2
(-7675 3050);
DISPLAY 0.510638 (-7675 3050);
PAINT SKYBLUE (-7675 3050);
FORCEPROP 2 LAST CDS_LIB pure_quanta
J 0
(-7825 2975);
DISPLAY INVISIBLE (-7825 2975);
FORCEPROP 1 LAST TOLERANCE 1%
J 0
(-7825 2875);
DISPLAY 0.978723 (-7825 2875);
DISPLAY INVISIBLE (-7825 2875);
FORCEPROP 1 LAST WATTAGE 1/16W
J 2
(-7850 2825);
DISPLAY 0.978723 (-7850 2825);
DISPLAY INVISIBLE (-7850 2825);
FORCEPROP 1 LAST PACK_TYPE 0402LF
J 0
(-7575 2825);
DISPLAY 0.978723 (-7575 2825);
DISPLAY INVISIBLE (-7575 2825);
FORCEPROP 1 LAST MATERIAL CHIP
J 0
(-7825 2825);
DISPLAY 0.978723 (-7825 2825);
DISPLAY INVISIBLE (-7825 2825);
FORCEPROP 1 LAST PATH I418
J 0
(-7875 3125);
DISPLAY 0.978723 (-7875 3125);
PAINT WHITE (-7875 3125);
DISPLAY INVISIBLE (-7875 3125);
FORCEPROP 1 LAST PART_NUMBER CS04992FB07
J 0
(-7875 3075);
DISPLAY 0.978723 (-7875 3075);
DISPLAY INVISIBLE (-7875 3075);
FORCEADD Q_RES..1
(-8125 3175);
FORCEPROP 1 LAST LOCATION R1679
J 0
(-8300 3175);
DISPLAY 0.510638 (-8300 3175);
FORCEPROP 0 LAST $SEC 1
J 0
(-8300 3225);
DISPLAY 0.680851 (-8300 3225);
PAINT MONO (-8300 3225);
DISPLAY INVISIBLE (-8300 3225);
FORCEPROP 0 LAST CDS_SEC 1
J 0
(-8300 3225);
DISPLAY 0.680851 (-8300 3225);
DISPLAY INVISIBLE (-8300 3225);
FORCEPROP 1 LASTPIN (-8225 3175) $PN 1
J 0
(-8213 3187);
DISPLAY 0.787234 (-8213 3187);
PAINT MONO (-8213 3187);
FORCEPROP 1 LASTPIN (-8025 3175) $PN 2
J 0
(-8063 3187);
DISPLAY 0.787234 (-8063 3187);
PAINT MONO (-8063 3187);
FORCEPROP 1 LAST MATERIAL CHIP
J 0
(-8225 3150);
DISPLAY 0.404255 (-8225 3150);
FORCEPROP 1 LAST PACK_TYPE 0402LF
J 0
(-8075 3150);
DISPLAY 0.404255 (-8075 3150);
FORCEPROP 1 LAST VALUE 10
J 2
(-7975 3175);
DISPLAY 0.404255 (-7975 3175);
FORCEPROP 1 LAST TOLERANCE 1%
J 0
(-8125 3075);
DISPLAY 0.978723 (-8125 3075);
DISPLAY INVISIBLE (-8125 3075);
FORCEPROP 1 LAST WATTAGE 1/16W
J 2
(-8150 3025);
DISPLAY 0.978723 (-8150 3025);
DISPLAY INVISIBLE (-8150 3025);
FORCEPROP 2 LAST CDS_LIB pure_quanta
J 0
(-8125 3175);
DISPLAY INVISIBLE (-8125 3175);
FORCEPROP 1 LAST PATH I419
J 0
(-8175 3325);
DISPLAY 0.978723 (-8175 3325);
PAINT WHITE (-8175 3325);
DISPLAY INVISIBLE (-8175 3325);
FORCEPROP 1 LAST PART_NUMBER CS01002FB07
J 0
(-8175 3275);
DISPLAY 0.978723 (-8175 3275);
DISPLAY INVISIBLE (-8175 3275);
FORCEADD OFFPAGE..6
(-8850 3075);
FORCEPROP 2 LAST $XR5 159 
J 0
(-9219 3039);
DISPLAY 0.638298 (-9219 3039);
PAINT MONO (-9219 3039);
FORCEPROP 2 LAST $XR4 90 
J 0
(-9099 3039);
DISPLAY 0.638298 (-9099 3039);
PAINT MONO (-9099 3039);
FORCEPROP 2 LAST $XR3 89 
J 0
(-9369 3075);
DISPLAY 0.638298 (-9369 3075);
PAINT MONO (-9369 3075);
FORCEPROP 2 LAST $XR2 88 
J 0
(-9279 3075);
DISPLAY 0.638298 (-9279 3075);
PAINT MONO (-9279 3075);
FORCEPROP 2 LAST $XR1 87 
J 0
(-9189 3075);
DISPLAY 0.638298 (-9189 3075);
PAINT MONO (-9189 3075);
FORCEPROP 2 LAST $XR0 86 
J 0
(-9099 3075);
DISPLAY 0.638298 (-9099 3075);
PAINT MONO (-9099 3075);
FORCEPROP 2 LAST CDS_LIB mstr_standard
J 0
(-8850 3075);
DISPLAY 0.808511 (-8850 3075);
DISPLAY INVISIBLE (-8850 3075);
FORCEPROP 1 LAST OFFPAGE TRUE
J 0
(-8525 2950);
DISPLAY 0.872340 (-8525 2950);
PAINT GREEN (-8525 2950);
DISPLAY INVISIBLE (-8525 2950);
FORCEPROP 1 LAST COMMENT_BODY TRUE
J 0
(-8750 3000);
DISPLAY 0.872340 (-8750 3000);
PAINT GREEN (-8750 3000);
DISPLAY INVISIBLE (-8750 3000);
FORCEPROP 2 LAST PATH I420
J 0
(-9125 3125);
DISPLAY 0.680851 (-9125 3125);
DISPLAY INVISIBLE (-9125 3125);
FORCEADD DNS..2
(-8400 2625);
PAINT RED (-8400 2625);
FORCEPROP 2 LAST CDS_LIB mstr_misc
J 0
(-8400 2625);
DISPLAY INVISIBLE (-8400 2625);
FORCEPROP 1 LAST COMMENT_BODY TRUE
R 1
J 0
(-8325 2400);
DISPLAY 0.872340 (-8325 2400);
PAINT PEACH (-8325 2400);
DISPLAY INVISIBLE (-8325 2400);
FORCEADD QUANTA_TITLE_BLOCK_C..1
(-100 100);
FORCEPROP 0 LAST CDS_CON_LAST_MODIFIED Thu Sep 14 16:12:07 2023
J 0
(-1985 115);
DISPLAY INVISIBLE (-1985 115);
FORCEPROP 1 LAST CUSTOM_TXT_CDS <CON_LAST_MODIFIED>
J 0
(-1985 115);
DISPLAY 0.978723 (-1985 115);
FORCEPROP 2 LAST CUSTOM_TXT_CDS <XR_PAGE_TITLE>
J 0
(-7990 5350);
DISPLAY 0.638298 (-7990 5350);
PAINT PINK (-7990 5350);
DISPLAY INVISIBLE (-7990 5350);
FORCEPROP 1 LAST CUSTOM_TXT_CDS <NAME_2>
J 0
(-3275 150);
FORCEPROP 1 LAST CUSTOM_TXT_CDS <NAME_1>
J 0
(-3275 275);
FORCEPROP 1 LAST CUSTOM_TXT_CDS <Q_NUMBER>
J 0
(-1503 203);
DISPLAY 1.212766 (-1503 203);
FORCEPROP 1 LAST CUSTOM_TXT_CDS <Q_PROJ>
J 0
(-2482 202);
DISPLAY 1.212766 (-2482 202);
FORCEPROP 1 LAST CUSTOM_TXT_CDS <Q_REV>
J 0
(-284 203);
DISPLAY 1.212766 (-284 203);
FORCEPROP 1 LAST CUSTOM_TXT_CDS <CON_PAGE_NUM> OF <CON_TOTAL_PAGES>
J 0
(-546 118);
DISPLAY 0.978723 (-546 118);
FORCEPROP 1 LAST Q_TITLE DDR5 - CPU0 CHF
J 0
(-9400 175);
DISPLAY 2.446809 (-9400 175);
PAINT GREEN (-9400 175);
FORCEPROP 2 LAST PAGE_BORDER TRUE
J 0
(-7990 5350);
DISPLAY 0.638298 (-7990 5350);
PAINT PINK (-7990 5350);
DISPLAY INVISIBLE (-7990 5350);
FORCEPROP 1 LAST CDS_LMAN_SYM_OUTLINE -9475,6775,100,-125
J 0
(-100 100);
DISPLAY 0.468085 (-100 100);
PAINT GREEN (-100 100);
DISPLAY INVISIBLE (-100 100);
FORCEPROP 2 LAST CDS_LIB pure_quanta
J 0
(-100 100);
DISPLAY INVISIBLE (-100 100);
FORCEPROP 2 LAST CDS_XR_PAGE_TITLE CR-91 : @T6G_MB_LIB.T6G(SCH_1):PAGE91
J 0
(-7990 5350);
DISPLAY 0.638298 (-7990 5350);
PAINT PINK (-7990 5350);
DISPLAY INVISIBLE (-7990 5350);
FORCEPROP 1 LAST Q_DEPT BU9
J 1
(-3863 149);
DISPLAY 1.957447 (-3863 149);
PAINT GREEN (-3863 149);
DISPLAY INVISIBLE (-3863 149);
FORCEPROP 1 LAST COMMENT_BODY TRUE
J 0
(-88 87);
DISPLAY 0.978723 (-88 87);
PAINT GREEN (-88 87);
DISPLAY INVISIBLE (-88 87);
WIRE 17 -1 (-7825 4000)(-7825 4050);
WIRE 17 -1 (-7825 4050)(-7825 4100);
WIRE 17 -1 (-7825 4100)(-7825 4150);
WIRE 17 -1 (-7825 4150)(-7825 4200);
WIRE 17 -1 (-7825 4250)(-7825 4200);
WIRE 17 -1 (-7825 4250)(-7825 4300);
WIRE 17 -1 (-7825 4350)(-7825 4300);
WIRE 17 -1 (-7825 4350)(-7825 4375);
WIRE 17 -1 (-7825 4375)(-8325 4375);
FORCEPROP 2 LAST SIG_NAME M_F_CPU0_SA_CB<7:0>
J 0
(-8275 4385);
DISPLAY 0.489362 (-8275 4385);
WIRE 17 -1 (-7825 3900)(-7825 3925);
WIRE 17 -1 (-7825 3900)(-7825 3850);
WIRE 17 -1 (-7825 3925)(-8325 3925);
FORCEPROP 2 LAST SIG_NAME M_F_CPU0_SB_CB<7:0>
J 0
(-8275 3935);
DISPLAY 0.489362 (-8275 3935);
WIRE 17 -1 (-7825 5450)(-7825 5500);
WIRE 17 -1 (-7825 5500)(-7825 5550);
WIRE 17 -1 (-7825 5550)(-7825 5600);
WIRE 17 -1 (-7825 5600)(-7825 5650);
WIRE 17 -1 (-7825 5650)(-7825 5700);
WIRE 17 -1 (-7825 5700)(-7825 5750);
WIRE 17 -1 (-7825 5750)(-7825 5775);
WIRE 17 -1 (-7825 5775)(-8325 5775);
FORCEPROP 2 LAST SIG_NAME M_F_CPU0_SA_CA<6:0>
J 0
(-8310 5785);
DISPLAY 0.489362 (-8310 5785);
WIRE 17 -1 (-7825 5050)(-7825 5100);
WIRE 17 -1 (-7825 5100)(-7825 5150);
WIRE 17 -1 (-7825 5150)(-7825 5200);
WIRE 17 -1 (-7825 5200)(-7825 5250);
WIRE 17 -1 (-7825 5250)(-7825 5300);
WIRE 17 -1 (-7825 5300)(-7825 5350);
WIRE 17 -1 (-7825 5350)(-7825 5375);
WIRE 17 -1 (-7825 5375)(-8325 5375);
FORCEPROP 2 LAST SIG_NAME M_F_CPU0_SB_CA<6:0>
J 0
(-8310 5385);
DISPLAY 0.489362 (-8310 5385);
WIRE 17 -1 (-7825 3800)(-7825 3850);
WIRE 17 -1 (-7825 3800)(-7825 3750);
WIRE 17 -1 (-7825 3700)(-7825 3750);
WIRE 17 -1 (-7825 3650)(-7825 3700);
WIRE 17 -1 (-7825 3600)(-7825 3650);
WIRE 17 -1 (-7825 3550)(-7825 3600);
WIRE 17 -1 (-6025 5750)(-6025 5700);
WIRE 17 -1 (-6025 5750)(-5500 5750);
FORCEPROP 2 LAST SIG_NAME M_F_CPU0_SA_DQ<31:0>
J 0
(-5960 5760);
DISPLAY 0.489362 (-5960 5760);
WIRE 17 -1 (-6025 5700)(-6025 5650);
WIRE 17 -1 (-6025 5650)(-6025 5600);
WIRE 17 -1 (-6025 5600)(-6025 5550);
WIRE 17 -1 (-6025 5550)(-6025 5500);
WIRE 17 -1 (-6025 5500)(-6025 5450);
WIRE 17 -1 (-6025 5450)(-6025 5400);
WIRE 17 -1 (-6025 5400)(-6025 5350);
WIRE 17 -1 (-6025 5350)(-6025 5300);
WIRE 17 -1 (-6025 5300)(-6025 5250);
WIRE 17 -1 (-6025 5250)(-6025 5200);
WIRE 17 -1 (-6025 5200)(-6025 5150);
WIRE 17 -1 (-6025 5150)(-6025 5100);
WIRE 17 -1 (-6025 5100)(-6025 5050);
WIRE 17 -1 (-6025 5050)(-6025 5000);
WIRE 17 -1 (-6025 4950)(-6025 5000);
WIRE 17 -1 (-6025 4900)(-6025 4950);
WIRE 17 -1 (-6025 4850)(-6025 4900);
WIRE 17 -1 (-6025 4800)(-6025 4850);
WIRE 17 -1 (-6025 4800)(-6025 4750);
WIRE 17 -1 (-6025 4750)(-6025 4700);
WIRE 17 -1 (-6025 4700)(-6025 4650);
WIRE 17 -1 (-6025 4650)(-6025 4600);
WIRE 17 -1 (-6025 4600)(-6025 4550);
WIRE 17 -1 (-6025 4550)(-6025 4500);
WIRE 17 -1 (-6025 4500)(-6025 4450);
WIRE 17 -1 (-6025 4450)(-6025 4400);
WIRE 17 -1 (-6025 4350)(-6025 4400);
WIRE 17 -1 (-6025 4300)(-6025 4350);
WIRE 17 -1 (-6025 4250)(-6025 4300);
WIRE 17 -1 (-6025 4200)(-6025 4250);
WIRE 17 -1 (-6025 4100)(-5500 4100);
FORCEPROP 2 LAST SIG_NAME M_F_CPU0_SB_DQ<31:0>
J 0
(-5960 4110);
DISPLAY 0.489362 (-5960 4110);
WIRE 17 -1 (-6025 4050)(-6025 4000);
WIRE 17 -1 (-6025 4100)(-6025 4050);
WIRE 17 -1 (-6025 4000)(-6025 3950);
WIRE 17 -1 (-6025 3950)(-6025 3900);
WIRE 17 -1 (-6025 3900)(-6025 3850);
WIRE 17 -1 (-6025 3850)(-6025 3800);
WIRE 17 -1 (-6025 3800)(-6025 3750);
WIRE 17 -1 (-6025 3750)(-6025 3700);
WIRE 17 -1 (-6025 3700)(-6025 3650);
WIRE 17 -1 (-6025 3650)(-6025 3600);
WIRE 17 -1 (-6025 3600)(-6025 3550);
WIRE 17 -1 (-6025 3550)(-6025 3500);
WIRE 17 -1 (-6025 3500)(-6025 3450);
WIRE 17 -1 (-6025 3450)(-6025 3400);
WIRE 17 -1 (-6025 3400)(-6025 3350);
WIRE 17 -1 (-6025 3300)(-6025 3350);
WIRE 17 -1 (-6025 3250)(-6025 3300);
WIRE 17 -1 (-6025 3200)(-6025 3250);
WIRE 17 -1 (-6025 3150)(-6025 3200);
WIRE 17 -1 (-6025 3150)(-6025 3100);
WIRE 17 -1 (-6025 3100)(-6025 3050);
WIRE 17 -1 (-6025 3050)(-6025 3000);
WIRE 17 -1 (-6025 3000)(-6025 2950);
WIRE 17 -1 (-6025 2950)(-6025 2900);
WIRE 17 -1 (-6025 2900)(-6025 2850);
WIRE 17 -1 (-6025 2850)(-6025 2800);
WIRE 17 -1 (-6025 2800)(-6025 2750);
WIRE 17 -1 (-6025 2700)(-6025 2750);
WIRE 17 -1 (-6025 2650)(-6025 2700);
WIRE 17 -1 (-6025 2600)(-6025 2650);
WIRE 17 -1 (-6025 2550)(-6025 2600);
WIRE 17 -1 (-3325 4700)(-3325 4600);
WIRE 17 -1 (-3325 4800)(-3325 4700);
WIRE 17 -1 (-3325 4600)(-3325 4500);
WIRE 17 -1 (-3325 4500)(-3325 4400);
WIRE 17 -1 (-3325 4825)(-3325 4800);
WIRE 17 -1 (-3325 4825)(-2625 4825);
FORCEPROP 2 LAST SIG_NAME M_F_CPU0_SA_DQS_DN<9:0>
J 0
(-3260 4835);
DISPLAY 0.489362 (-3260 4835);
WIRE 17 -1 (-3525 4650)(-3525 4550);
WIRE 17 -1 (-3525 4750)(-3525 4650);
WIRE 17 -1 (-3525 4550)(-3525 4450);
WIRE 17 -1 (-3525 4350)(-3525 4450);
WIRE 17 -1 (-3525 4850)(-3525 4750);
WIRE 17 -1 (-3525 4875)(-3525 4850);
WIRE 17 -1 (-3525 4250)(-3525 4350);
WIRE 17 -1 (-3525 4150)(-3525 4250);
WIRE 17 -1 (-3525 4875)(-2625 4875);
FORCEPROP 2 LAST SIG_NAME M_F_CPU0_SA_DQS_DP<9:0>
J 0
(-3260 4885);
DISPLAY 0.489362 (-3260 4885);
WIRE 17 -1 (-3525 3800)(-3525 3700);
WIRE 17 -1 (-3525 3825)(-3525 3800);
WIRE 17 -1 (-3525 3700)(-3525 3600);
WIRE 17 -1 (-3525 3600)(-3525 3500);
WIRE 17 -1 (-3525 3825)(-2625 3825);
FORCEPROP 2 LAST SIG_NAME M_F_CPU0_SB_DQS_DP<9:0>
J 0
(-3260 3835);
DISPLAY 0.489362 (-3260 3835);
WIRE 17 -1 (-3325 3750)(-3325 3650);
WIRE 17 -1 (-3325 3775)(-3325 3750);
WIRE 17 -1 (-3325 3650)(-3325 3550);
WIRE 17 -1 (-3325 3550)(-3325 3450);
WIRE 17 -1 (-3325 3775)(-2625 3775);
FORCEPROP 2 LAST SIG_NAME M_F_CPU0_SB_DQS_DN<9:0>
J 0
(-3260 3785);
DISPLAY 0.489362 (-3260 3785);
WIRE 17 -1 (-3525 3500)(-3525 3400);
WIRE 17 -1 (-3325 4000)(-3325 3900);
WIRE 17 -1 (-3325 4100)(-3325 4000);
WIRE 17 -1 (-3325 4100)(-3325 4200);
WIRE 17 -1 (-3325 4200)(-3325 4300);
WIRE 17 -1 (-3325 4300)(-3325 4400);
WIRE 17 -1 (-3525 4050)(-3525 3950);
WIRE 17 -1 (-3525 4150)(-3525 4050);
WIRE 17 -1 (-3325 2950)(-3325 2850);
WIRE 17 -1 (-3325 3050)(-3325 2950);
WIRE 17 -1 (-3325 3050)(-3325 3150);
WIRE 17 -1 (-3325 3150)(-3325 3250);
WIRE 17 -1 (-3325 3250)(-3325 3350);
WIRE 17 -1 (-3325 3450)(-3325 3350);
WIRE 17 -1 (-3525 3000)(-3525 2900);
WIRE 17 -1 (-3525 3100)(-3525 3000);
WIRE 17 -1 (-3525 3100)(-3525 3200);
WIRE 17 -1 (-3525 3200)(-3525 3300);
WIRE 17 -1 (-3525 3300)(-3525 3400);
WIRE 16 -1 (-6400 1425)(-6400 1500);
WIRE 16 -1 (-8650 3400)(-8650 3475);
WIRE 16 -1 (-8425 2725)(-8425 2750);
WIRE 16 -1 (-7525 3375)(-8125 3375);
FORCEPROP 2 LAST SIG_NAME M_F_CPU0_ALERT_N
J 0
(-8110 3385);
DISPLAY 0.489362 (-8110 3385);
WIRE 16 -1 (-7925 2975)(-8400 2975);
FORCEPROP 2 LAST SIG_NAME I3C_SPD_DDRAF_CPU0_SCL
J 0
(-8460 2985);
DISPLAY 0.489362 (-8460 2985);
WIRE 16 -1 (-7525 3125)(-7625 3125);
FORCEPROP 2 LAST SIG_NAME I3C_SPD_DDRF_CPU0_SCL
J 0
(-8060 3100);
DISPLAY 0.446809 (-8060 3100);
FORCEPROP 2 LASTPROP $XRERR UNIQUE?
J 0
(-8300 3100);
DISPLAY 0.638298 (-8300 3100);
PAINT MONO (-8300 3100);
DISPLAY INVISIBLE (-8300 3100);
WIRE 16 -1 (-7625 3125)(-7625 2975);
WIRE 16 -1 (-7625 2975)(-7725 2975);
WIRE 16 -1 (-8225 2475)(-8225 2875);
WIRE 16 -1 (-8225 2475)(-8425 2475);
WIRE 16 -1 (-7525 2875)(-8225 2875);
FORCEPROP 2 LAST SIG_NAME PWRGD_CHF_CPU0_DIMM
J 0
(-8125 2885);
DISPLAY 0.489362 (-8125 2885);
FORCEPROP 2 LASTPROP $XRERR UNIQUE?
J 0
(-8365 2885);
DISPLAY 0.638298 (-8365 2885);
PAINT MONO (-8365 2885);
DISPLAY INVISIBLE (-8365 2885);
WIRE 16 -1 (-8425 2525)(-8425 2475);
WIRE 16 -1 (-8425 2475)(-8450 2475);
WIRE 16 -1 (-8275 3175)(-8225 3175);
WIRE 16 -1 (-8275 3075)(-8275 3175);
WIRE 16 -1 (-8275 3075)(-8800 3075);
FORCEPROP 2 LAST SIG_NAME I3C_SPD_DDRAF_CPU0_SDA
J 0
(-8810 3085);
DISPLAY 0.489362 (-8810 3085);
WIRE 16 -1 (-7525 3175)(-8025 3175);
FORCEPROP 2 LAST SIG_NAME I3C_SPD_DDRF_CPU0_SDA
J 0
(-7935 3185);
DISPLAY 0.361702 (-7935 3185);
FORCEPROP 2 LASTPROP $XRERR UNIQUE?
J 0
(-8175 3185);
DISPLAY 0.638298 (-8175 3185);
PAINT MONO (-8175 3185);
DISPLAY INVISIBLE (-8175 3185);
WIRE 16 -1 (-7525 3225)(-8325 3225);
FORCEPROP 2 LAST SIG_NAME PD_CHF_CPU0_DIMM_SAA
J 0
(-8300 3235);
DISPLAY 0.489362 (-8300 3235);
WIRE 16 -1 (-8650 3675)(-8650 3700);
WIRE 16 -1 (-8650 3700)(-8550 3700);
WIRE 16 -1 (-8550 3725)(-8550 3700);
WIRE 16 -1 (-8550 3700)(-8550 3275);
WIRE 16 -1 (-8550 3275)(-7525 3275);
WIRE 16 -1 (-7525 3525)(-7725 3525);
WIRE 16 -1 (-7525 3575)(-7725 3575);
WIRE 16 -1 (-9000 2475)(-8650 2475);
FORCEPROP 2 LAST SIG_NAME PWRGD_CHAF_CPU0
J 0
(-8985 2485);
DISPLAY 0.489362 (-8985 2485);
WIRE 16 -1 (-6125 3825)(-6325 3825);
WIRE 16 -1 (-6125 3925)(-6325 3925);
WIRE 16 -1 (-6125 4025)(-6325 4025);
WIRE 16 -1 (-7525 5075)(-7725 5075);
WIRE 16 -1 (-6125 4875)(-6325 4875);
WIRE 16 -1 (-3775 3775)(-3625 3775);
WIRE 16 -1 (-3775 3725)(-3425 3725);
WIRE 16 -1 (-3775 4825)(-3625 4825);
WIRE 16 -1 (-3775 4775)(-3425 4775);
WIRE 16 -1 (-3625 4725)(-3775 4725);
WIRE 16 -1 (-3775 4675)(-3425 4675);
WIRE 16 -1 (-3775 3525)(-3425 3525);
WIRE 16 -1 (-3625 4625)(-3775 4625);
WIRE 16 -1 (-3625 3475)(-3775 3475);
WIRE 16 -1 (-3775 3425)(-3425 3425);
WIRE 16 -1 (-3775 4475)(-3425 4475);
WIRE 16 -1 (-3775 3375)(-3625 3375);
WIRE 16 -1 (-3775 3325)(-3425 3325);
WIRE 16 -1 (-3775 4425)(-3625 4425);
WIRE 16 -1 (-3775 4375)(-3425 4375);
WIRE 16 -1 (-3625 3275)(-3775 3275);
WIRE 16 -1 (-3775 3225)(-3425 3225);
WIRE 16 -1 (-3625 4325)(-3775 4325);
WIRE 16 -1 (-3775 4275)(-3425 4275);
WIRE 16 -1 (-3625 3175)(-3775 3175);
WIRE 16 -1 (-3775 3125)(-3425 3125);
WIRE 16 -1 (-3625 4225)(-3775 4225);
WIRE 16 -1 (-3775 4175)(-3425 4175);
WIRE 16 -1 (-3625 3075)(-3775 3075);
WIRE 16 -1 (-3775 3025)(-3425 3025);
WIRE 16 -1 (-3625 4125)(-3775 4125);
WIRE 16 -1 (-3775 4075)(-3425 4075);
WIRE 16 -1 (-3775 2975)(-3625 2975);
WIRE 16 -1 (-3775 2925)(-3425 2925);
WIRE 16 -1 (-3775 4025)(-3625 4025);
WIRE 16 -1 (-3775 3975)(-3425 3975);
WIRE 16 -1 (-3625 2875)(-3775 2875);
WIRE 16 -1 (-3775 2825)(-3425 2825);
WIRE 16 -1 (-3625 3925)(-3775 3925);
WIRE 16 -1 (-3775 3875)(-3425 3875);
WIRE 16 -1 (-3625 3575)(-3775 3575);
WIRE 16 -1 (-3775 3625)(-3425 3625);
WIRE 16 -1 (-3625 3675)(-3775 3675);
WIRE 16 -1 (-3625 4525)(-3775 4525);
WIRE 16 -1 (-3775 4575)(-3425 4575);
WIRE 16 -1 (-6125 5275)(-6325 5275);
WIRE 16 -1 (-7525 4875)(-8325 4875);
FORCEPROP 2 LAST SIG_NAME M_F_CPU0_SB_PAR
J 0
(-8275 4885);
DISPLAY 0.489362 (-8275 4885);
WIRE 16 -1 (-7525 4925)(-8325 4925);
FORCEPROP 2 LAST SIG_NAME M_F_CPU0_SA_PAR
J 0
(-8275 4935);
DISPLAY 0.489362 (-8275 4935);
WIRE 16 -1 (-7525 5675)(-7725 5675);
WIRE 16 -1 (-7525 5725)(-7725 5725);
WIRE 16 -1 (-6125 5575)(-6325 5575);
WIRE 16 -1 (-6325 5725)(-6125 5725);
WIRE 16 -1 (-7525 2275)(-8325 2275);
FORCEPROP 2 LAST SIG_NAME M_F_CPU0_SB_RSP<0>
J 0
(-8275 2285);
DISPLAY 0.489362 (-8275 2285);
WIRE 16 -1 (-7525 2325)(-8325 2325);
FORCEPROP 2 LAST SIG_NAME M_F_CPU0_SA_RSP<0>
J 0
(-8275 2335);
DISPLAY 0.489362 (-8275 2335);
WIRE 16 -1 (-6125 2525)(-6325 2525);
WIRE 16 -1 (-6125 2575)(-6325 2575);
WIRE 16 -1 (-6125 2625)(-6325 2625);
WIRE 16 -1 (-6325 2675)(-6125 2675);
WIRE 16 -1 (-6125 2725)(-6325 2725);
WIRE 16 -1 (-6125 2775)(-6325 2775);
WIRE 16 -1 (-6125 2825)(-6325 2825);
WIRE 16 -1 (-6325 2875)(-6125 2875);
WIRE 16 -1 (-6125 2925)(-6325 2925);
WIRE 16 -1 (-6125 2975)(-6325 2975);
WIRE 16 -1 (-6125 3025)(-6325 3025);
WIRE 16 -1 (-6325 3075)(-6125 3075);
WIRE 16 -1 (-6125 3125)(-6325 3125);
WIRE 16 -1 (-6125 3175)(-6325 3175);
WIRE 16 -1 (-6125 3225)(-6325 3225);
WIRE 16 -1 (-6325 3275)(-6125 3275);
WIRE 16 -1 (-6125 3325)(-6325 3325);
WIRE 16 -1 (-6125 3375)(-6325 3375);
WIRE 16 -1 (-6125 3425)(-6325 3425);
WIRE 16 -1 (-6325 3475)(-6125 3475);
WIRE 16 -1 (-6125 3525)(-6325 3525);
WIRE 16 -1 (-6125 3575)(-6325 3575);
WIRE 16 -1 (-6125 3625)(-6325 3625);
WIRE 16 -1 (-6325 3675)(-6125 3675);
WIRE 16 -1 (-6125 3725)(-6325 3725);
WIRE 16 -1 (-6125 3775)(-6325 3775);
WIRE 16 -1 (-6325 3875)(-6125 3875);
WIRE 16 -1 (-6125 3975)(-6325 3975);
WIRE 16 -1 (-6325 4075)(-6125 4075);
WIRE 16 -1 (-6125 4175)(-6325 4175);
WIRE 16 -1 (-6125 4225)(-6325 4225);
WIRE 16 -1 (-6125 4275)(-6325 4275);
WIRE 16 -1 (-6325 4325)(-6125 4325);
WIRE 16 -1 (-6125 4375)(-6325 4375);
WIRE 16 -1 (-6125 4425)(-6325 4425);
WIRE 16 -1 (-6125 4475)(-6325 4475);
WIRE 16 -1 (-6325 4525)(-6125 4525);
WIRE 16 -1 (-6125 4575)(-6325 4575);
WIRE 16 -1 (-6125 4625)(-6325 4625);
WIRE 16 -1 (-6125 4675)(-6325 4675);
WIRE 16 -1 (-6325 4725)(-6125 4725);
WIRE 16 -1 (-6125 4775)(-6325 4775);
WIRE 16 -1 (-6125 4825)(-6325 4825);
WIRE 16 -1 (-6325 4925)(-6125 4925);
WIRE 16 -1 (-6125 4975)(-6325 4975);
WIRE 16 -1 (-6125 5025)(-6325 5025);
WIRE 16 -1 (-6125 5075)(-6325 5075);
WIRE 16 -1 (-6325 5125)(-6125 5125);
WIRE 16 -1 (-6125 5175)(-6325 5175);
WIRE 16 -1 (-6125 5225)(-6325 5225);
WIRE 16 -1 (-6325 5325)(-6125 5325);
WIRE 16 -1 (-6125 5375)(-6325 5375);
WIRE 16 -1 (-6125 5425)(-6325 5425);
WIRE 16 -1 (-6125 5475)(-6325 5475);
WIRE 16 -1 (-6325 5525)(-6125 5525);
WIRE 16 -1 (-6125 5625)(-6325 5625);
WIRE 16 -1 (-6125 5675)(-6325 5675);
WIRE 16 -1 (-7525 4625)(-8325 4625);
FORCEPROP 2 LAST SIG_NAME M_F_CPU0_SB_CS_N<1>
J 0
(-8275 4635);
DISPLAY 0.489362 (-8275 4635);
WIRE 16 -1 (-7525 4775)(-8325 4775);
FORCEPROP 2 LAST SIG_NAME M_F_CPU0_SA_CS_N<1>
J 0
(-8275 4785);
DISPLAY 0.489362 (-8275 4785);
WIRE 16 -1 (-7525 4575)(-8325 4575);
FORCEPROP 2 LAST SIG_NAME M_F_CPU0_SB_CS_N<0>
J 0
(-8275 4585);
DISPLAY 0.489362 (-8275 4585);
WIRE 16 -1 (-7525 4725)(-8325 4725);
FORCEPROP 2 LAST SIG_NAME M_F_CPU0_SA_CS_N<0>
J 0
(-8275 4735);
DISPLAY 0.489362 (-8275 4735);
WIRE 16 -1 (-7525 4475)(-8325 4475);
FORCEPROP 2 LAST SIG_NAME M_F_CPU0_CLK_DP<0>
J 0
(-8275 4485);
DISPLAY 0.489362 (-8275 4485);
WIRE 16 -1 (-7525 4425)(-8325 4425);
FORCEPROP 2 LAST SIG_NAME M_F_CPU0_CLK_DN<0>
J 0
(-8275 4435);
DISPLAY 0.489362 (-8275 4435);
WIRE 16 -1 (-7525 3625)(-7725 3625);
WIRE 16 -1 (-7525 3675)(-7725 3675);
WIRE 16 -1 (-7525 3725)(-7725 3725);
WIRE 16 -1 (-7525 3775)(-7725 3775);
WIRE 16 -1 (-7525 3825)(-7725 3825);
WIRE 16 -1 (-7525 4075)(-7725 4075);
WIRE 16 -1 (-7525 4125)(-7725 4125);
WIRE 16 -1 (-7525 4275)(-7725 4275);
WIRE 16 -1 (-7525 5325)(-7725 5325);
WIRE 16 -1 (-7525 5275)(-7725 5275);
WIRE 16 -1 (-7525 5225)(-7725 5225);
WIRE 16 -1 (-7525 5625)(-7725 5625);
WIRE 16 -1 (-7525 5175)(-7725 5175);
WIRE 16 -1 (-7525 5575)(-7725 5575);
WIRE 16 -1 (-7525 5125)(-7725 5125);
WIRE 16 -1 (-7525 5525)(-7725 5525);
WIRE 16 -1 (-7525 5475)(-7725 5475);
WIRE 16 -1 (-7525 5025)(-7725 5025);
WIRE 16 -1 (-7525 5425)(-7725 5425);
WIRE 16 -1 (-7525 3875)(-7725 3875);
WIRE 16 -1 (-7525 4325)(-7725 4325);
WIRE 16 -1 (-6400 1775)(-6400 1700);
WIRE 16 -1 (-6400 1775)(-7125 1775);
FORCEPROP 2 LAST SIG_NAME PD_CHF_CPU0_DIMM_SAA
J 0
(-7110 1785);
DISPLAY 0.489362 (-7110 1785);
WIRE 16 -1 (-7525 4225)(-7725 4225);
WIRE 16 -1 (-7525 4175)(-7725 4175);
WIRE 16 -1 (-7525 4025)(-7725 4025);
WIRE 16 -1 (-7525 3975)(-7725 3975);
WIRE 16 -1 (-7525 3425)(-8125 3425);
FORCEPROP 2 LAST SIG_NAME M_F_CPU0_RESET_N
J 0
(-8110 3435);
DISPLAY 0.489362 (-8110 3435);
WIRE 16 -1 (-1925 2400)(-2225 2400);
WIRE 16 -1 (-2225 2450)(-2225 2400);
WIRE 16 -1 (-2225 2400)(-2225 2350);
WIRE 16 -1 (-1925 2350)(-2225 2350);
WIRE 16 -1 (-2225 2350)(-2225 2225);
WIRE 16 -1 (-1925 2450)(-2225 2450);
WIRE 16 -1 (-2225 2500)(-2225 2450);
WIRE 16 -1 (-1925 2500)(-2225 2500);
WIRE 16 -1 (-2225 2550)(-2225 2500);
WIRE 16 -1 (-1925 2550)(-2225 2550);
WIRE 16 -1 (-2225 2600)(-2225 2550);
WIRE 16 -1 (-1925 2600)(-2225 2600);
WIRE 16 -1 (-2225 2650)(-2225 2600);
WIRE 16 -1 (-1925 2650)(-2225 2650);
WIRE 16 -1 (-2225 2700)(-2225 2650);
WIRE 16 -1 (-1925 2700)(-2225 2700);
WIRE 16 -1 (-2225 2750)(-2225 2700);
WIRE 16 -1 (-1925 2750)(-2225 2750);
WIRE 16 -1 (-2225 2800)(-2225 2750);
WIRE 16 -1 (-1925 2800)(-2225 2800);
WIRE 16 -1 (-2225 2850)(-2225 2800);
WIRE 16 -1 (-1925 2850)(-2225 2850);
WIRE 16 -1 (-2225 2900)(-2225 2850);
WIRE 16 -1 (-1925 2900)(-2225 2900);
WIRE 16 -1 (-2225 2950)(-2225 2900);
WIRE 16 -1 (-1925 2950)(-2225 2950);
WIRE 16 -1 (-2225 3000)(-2225 2950);
WIRE 16 -1 (-1925 3000)(-2225 3000);
WIRE 16 -1 (-2225 3050)(-2225 3000);
WIRE 16 -1 (-1925 3050)(-2225 3050);
WIRE 16 -1 (-2225 3100)(-2225 3050);
WIRE 16 -1 (-1925 3100)(-2225 3100);
WIRE 16 -1 (-2225 3150)(-2225 3100);
WIRE 16 -1 (-1925 3150)(-2225 3150);
WIRE 16 -1 (-2225 3200)(-2225 3150);
WIRE 16 -1 (-1925 3200)(-2225 3200);
WIRE 16 -1 (-2225 3250)(-2225 3200);
WIRE 16 -1 (-1925 3250)(-2225 3250);
WIRE 16 -1 (-2225 3300)(-2225 3250);
WIRE 16 -1 (-1925 3300)(-2225 3300);
WIRE 16 -1 (-2225 3350)(-2225 3300);
WIRE 16 -1 (-1925 3350)(-2225 3350);
WIRE 16 -1 (-2225 3400)(-2225 3350);
WIRE 16 -1 (-1925 3400)(-2225 3400);
WIRE 16 -1 (-2225 3450)(-2225 3400);
WIRE 16 -1 (-1925 3450)(-2225 3450);
WIRE 16 -1 (-2225 3500)(-2225 3450);
WIRE 16 -1 (-1925 3500)(-2225 3500);
WIRE 16 -1 (-2225 3550)(-2225 3500);
WIRE 16 -1 (-1925 3550)(-2225 3550);
WIRE 16 -1 (-2225 3600)(-2225 3550);
WIRE 16 -1 (-1925 3600)(-2225 3600);
WIRE 16 -1 (-2225 3650)(-2225 3600);
WIRE 16 -1 (-1925 3650)(-2225 3650);
WIRE 16 -1 (-2225 3700)(-2225 3650);
WIRE 16 -1 (-1925 3700)(-2225 3700);
WIRE 16 -1 (-2225 3750)(-2225 3700);
WIRE 16 -1 (-1925 3750)(-2225 3750);
WIRE 16 -1 (-2225 3800)(-2225 3750);
WIRE 16 -1 (-1925 3800)(-2225 3800);
WIRE 16 -1 (-2225 3850)(-2225 3800);
WIRE 16 -1 (-1925 3850)(-2225 3850);
WIRE 16 -1 (-2225 3900)(-2225 3850);
WIRE 16 -1 (-1925 3900)(-2225 3900);
WIRE 16 -1 (-2225 3950)(-2225 3900);
WIRE 16 -1 (-1925 3950)(-2225 3950);
WIRE 16 -1 (-2225 4000)(-2225 3950);
WIRE 16 -1 (-1925 4000)(-2225 4000);
WIRE 16 -1 (-2225 4050)(-2225 4000);
WIRE 16 -1 (-2225 4100)(-2225 4050);
WIRE 16 -1 (-1925 4050)(-2225 4050);
WIRE 16 -1 (-1925 4100)(-2225 4100);
WIRE 16 -1 (-2225 4150)(-2225 4100);
WIRE 16 -1 (-1925 4150)(-2225 4150);
WIRE 16 -1 (-2225 4200)(-2225 4150);
WIRE 16 -1 (-1925 4200)(-2225 4200);
WIRE 16 -1 (-2225 4250)(-2225 4200);
WIRE 16 -1 (-1925 4250)(-2225 4250);
WIRE 16 -1 (-2225 4300)(-2225 4250);
WIRE 16 -1 (-1925 4300)(-2225 4300);
WIRE 16 -1 (-2225 4350)(-2225 4300);
WIRE 16 -1 (-1925 4350)(-2225 4350);
WIRE 16 -1 (-2225 4400)(-2225 4350);
WIRE 16 -1 (-1925 4400)(-2225 4400);
WIRE 16 -1 (-2225 4450)(-2225 4400);
WIRE 16 -1 (-1925 4450)(-2225 4450);
WIRE 16 -1 (-2225 4500)(-2225 4450);
WIRE 16 -1 (-1925 4500)(-2225 4500);
WIRE 16 -1 (-2225 4550)(-2225 4500);
WIRE 16 -1 (-1925 4550)(-2225 4550);
WIRE 16 -1 (-2225 4600)(-2225 4550);
WIRE 16 -1 (-1925 4600)(-2225 4600);
WIRE 16 -1 (-2225 4650)(-2225 4600);
WIRE 16 -1 (-1925 4650)(-2225 4650);
WIRE 16 -1 (-2225 4700)(-2225 4650);
WIRE 16 -1 (-1925 4700)(-2225 4700);
WIRE 16 -1 (-2225 4750)(-2225 4700);
WIRE 16 -1 (-1925 4750)(-2225 4750);
WIRE 16 -1 (-2225 4800)(-2225 4750);
WIRE 16 -1 (-1925 4800)(-2225 4800);
WIRE 16 -1 (-2225 4850)(-2225 4800);
WIRE 16 -1 (-1925 4850)(-2225 4850);
WIRE 16 -1 (-2225 4900)(-2225 4850);
WIRE 16 -1 (-1925 4900)(-2225 4900);
WIRE 16 -1 (-2225 4950)(-2225 4900);
WIRE 16 -1 (-1925 4950)(-2225 4950);
WIRE 16 -1 (-2225 5000)(-2225 4950);
WIRE 16 -1 (-1925 5000)(-2225 5000);
WIRE 16 -1 (-2225 5050)(-2225 5000);
WIRE 16 -1 (-1925 5050)(-2225 5050);
WIRE 16 -1 (-2225 5100)(-2225 5050);
WIRE 16 -1 (-1925 5100)(-2225 5100);
WIRE 16 -1 (-2225 5150)(-2225 5100);
WIRE 16 -1 (-1925 5150)(-2225 5150);
WIRE 16 -1 (-2225 5200)(-2225 5150);
WIRE 16 -1 (-1925 5200)(-2225 5200);
WIRE 16 -1 (-2225 5250)(-2225 5200);
WIRE 16 -1 (-1925 5250)(-2225 5250);
WIRE 16 -1 (-2225 5300)(-2225 5250);
WIRE 16 -1 (-1925 5300)(-2225 5300);
WIRE 16 -1 (-2225 5350)(-2225 5300);
WIRE 16 -1 (-1925 5350)(-2225 5350);
WIRE 16 -1 (-2225 5400)(-2225 5350);
WIRE 16 -1 (-1925 5400)(-2225 5400);
WIRE 16 -1 (-2225 5450)(-2225 5400);
WIRE 16 -1 (-1925 5450)(-2225 5450);
WIRE 16 -1 (-425 2450)(-425 2350);
WIRE 16 -1 (-425 2500)(-425 2450);
WIRE 16 -1 (-425 2450)(-725 2450);
WIRE 16 -1 (-425 2350)(-425 2300);
WIRE 16 -1 (-425 2350)(-725 2350);
WIRE 16 -1 (-425 2300)(-425 2250);
WIRE 16 -1 (-425 2300)(-725 2300);
WIRE 16 -1 (-425 2550)(-425 2500);
WIRE 16 -1 (-425 2500)(-725 2500);
WIRE 16 -1 (-425 2600)(-425 2550);
WIRE 16 -1 (-425 2550)(-725 2550);
WIRE 16 -1 (-425 2250)(-725 2250);
WIRE 16 -1 (-425 2250)(-425 2000);
WIRE 16 -1 (-425 2650)(-425 2600);
WIRE 16 -1 (-425 2600)(-725 2600);
WIRE 16 -1 (-425 2700)(-425 2650);
WIRE 16 -1 (-425 2650)(-725 2650);
WIRE 16 -1 (-425 2750)(-425 2700);
WIRE 16 -1 (-425 2700)(-725 2700);
WIRE 16 -1 (-425 2800)(-425 2750);
WIRE 16 -1 (-425 2750)(-725 2750);
WIRE 16 -1 (-425 2850)(-425 2800);
WIRE 16 -1 (-425 2800)(-725 2800);
WIRE 16 -1 (-425 2900)(-425 2850);
WIRE 16 -1 (-425 2850)(-725 2850);
WIRE 16 -1 (-425 2950)(-425 2900);
WIRE 16 -1 (-425 2900)(-725 2900);
WIRE 16 -1 (-425 3000)(-425 2950);
WIRE 16 -1 (-425 2950)(-725 2950);
WIRE 16 -1 (-425 3050)(-425 3000);
WIRE 16 -1 (-425 3000)(-725 3000);
WIRE 16 -1 (-425 3100)(-425 3050);
WIRE 16 -1 (-425 3050)(-725 3050);
WIRE 16 -1 (-425 3150)(-425 3100);
WIRE 16 -1 (-425 3100)(-725 3100);
WIRE 16 -1 (-425 3200)(-425 3150);
WIRE 16 -1 (-425 3150)(-725 3150);
WIRE 16 -1 (-425 3250)(-425 3200);
WIRE 16 -1 (-425 3200)(-725 3200);
WIRE 16 -1 (-425 3300)(-425 3250);
WIRE 16 -1 (-425 3250)(-725 3250);
WIRE 16 -1 (-425 3350)(-425 3300);
WIRE 16 -1 (-425 3300)(-725 3300);
WIRE 16 -1 (-425 3400)(-425 3350);
WIRE 16 -1 (-425 3350)(-725 3350);
WIRE 16 -1 (-425 3450)(-425 3400);
WIRE 16 -1 (-425 3400)(-725 3400);
WIRE 16 -1 (-425 3500)(-425 3450);
WIRE 16 -1 (-425 3450)(-725 3450);
WIRE 16 -1 (-425 3550)(-425 3500);
WIRE 16 -1 (-425 3500)(-725 3500);
WIRE 16 -1 (-425 3600)(-425 3550);
WIRE 16 -1 (-425 3550)(-725 3550);
WIRE 16 -1 (-425 3650)(-425 3600);
WIRE 16 -1 (-425 3600)(-725 3600);
WIRE 16 -1 (-425 3700)(-425 3650);
WIRE 16 -1 (-425 3650)(-725 3650);
WIRE 16 -1 (-425 3750)(-425 3700);
WIRE 16 -1 (-425 3700)(-725 3700);
WIRE 16 -1 (-425 3800)(-425 3750);
WIRE 16 -1 (-425 3750)(-725 3750);
WIRE 16 -1 (-425 3850)(-425 3800);
WIRE 16 -1 (-425 3800)(-725 3800);
WIRE 16 -1 (-425 3900)(-425 3850);
WIRE 16 -1 (-425 3850)(-725 3850);
WIRE 16 -1 (-425 3950)(-425 3900);
WIRE 16 -1 (-425 3900)(-725 3900);
WIRE 16 -1 (-425 4000)(-425 3950);
WIRE 16 -1 (-425 3950)(-725 3950);
WIRE 16 -1 (-425 4050)(-425 4000);
WIRE 16 -1 (-425 4000)(-725 4000);
WIRE 16 -1 (-425 4100)(-425 4050);
WIRE 16 -1 (-425 4050)(-725 4050);
WIRE 16 -1 (-425 4150)(-425 4100);
WIRE 16 -1 (-425 4100)(-725 4100);
WIRE 16 -1 (-425 4200)(-425 4150);
WIRE 16 -1 (-425 4150)(-725 4150);
WIRE 16 -1 (-425 4250)(-425 4200);
WIRE 16 -1 (-425 4200)(-725 4200);
WIRE 16 -1 (-425 4300)(-425 4250);
WIRE 16 -1 (-425 4250)(-725 4250);
WIRE 16 -1 (-425 4350)(-425 4300);
WIRE 16 -1 (-425 4300)(-725 4300);
WIRE 16 -1 (-425 4400)(-425 4350);
WIRE 16 -1 (-425 4350)(-725 4350);
WIRE 16 -1 (-425 4450)(-425 4400);
WIRE 16 -1 (-425 4400)(-725 4400);
WIRE 16 -1 (-425 4500)(-425 4450);
WIRE 16 -1 (-425 4450)(-725 4450);
WIRE 16 -1 (-425 4550)(-425 4500);
WIRE 16 -1 (-425 4500)(-725 4500);
WIRE 16 -1 (-425 4600)(-425 4550);
WIRE 16 -1 (-425 4550)(-725 4550);
WIRE 16 -1 (-425 4650)(-425 4600);
WIRE 16 -1 (-425 4600)(-725 4600);
WIRE 16 -1 (-425 4700)(-425 4650);
WIRE 16 -1 (-425 4650)(-725 4650);
WIRE 16 -1 (-425 4750)(-425 4700);
WIRE 16 -1 (-425 4700)(-725 4700);
WIRE 16 -1 (-425 4800)(-425 4750);
WIRE 16 -1 (-425 4750)(-725 4750);
WIRE 16 -1 (-425 4850)(-425 4800);
WIRE 16 -1 (-425 4800)(-725 4800);
WIRE 16 -1 (-425 4900)(-425 4850);
WIRE 16 -1 (-425 4850)(-725 4850);
WIRE 16 -1 (-425 4950)(-425 4900);
WIRE 16 -1 (-425 4900)(-725 4900);
WIRE 16 -1 (-425 5000)(-425 4950);
WIRE 16 -1 (-425 4950)(-725 4950);
WIRE 16 -1 (-425 5050)(-425 5000);
WIRE 16 -1 (-425 5000)(-725 5000);
WIRE 16 -1 (-425 5100)(-425 5050);
WIRE 16 -1 (-425 5050)(-725 5050);
WIRE 16 -1 (-425 5150)(-425 5100);
WIRE 16 -1 (-425 5100)(-725 5100);
WIRE 16 -1 (-425 5200)(-425 5150);
WIRE 16 -1 (-425 5150)(-725 5150);
WIRE 16 -1 (-425 5250)(-425 5200);
WIRE 16 -1 (-425 5200)(-725 5200);
WIRE 16 -1 (-425 5300)(-425 5250);
WIRE 16 -1 (-425 5250)(-725 5250);
WIRE 16 -1 (-425 5350)(-425 5300);
WIRE 16 -1 (-425 5300)(-725 5300);
WIRE 16 -1 (-425 5400)(-425 5350);
WIRE 16 -1 (-425 5350)(-725 5350);
WIRE 16 -1 (-425 5450)(-425 5400);
WIRE 16 -1 (-425 5400)(-725 5400);
WIRE 16 -1 (-425 5500)(-425 5450);
WIRE 16 -1 (-425 5450)(-725 5450);
WIRE 16 -1 (-425 5550)(-425 5500);
WIRE 16 -1 (-425 5500)(-725 5500);
WIRE 16 -1 (-425 5600)(-425 5550);
WIRE 16 -1 (-425 5550)(-725 5550);
WIRE 16 -1 (-425 5600)(-725 5600);
WIRE 16 -1 (-2350 5925)(-2350 6050);
WIRE 16 -1 (-2350 5925)(-2925 5925);
WIRE 16 -1 (-2925 5925)(-2925 6050);
WIRE 16 -1 (-2925 5925)(-2925 5850);
WIRE 16 -1 (-2350 6350)(-2225 6350);
WIRE 16 -1 (-2350 6350)(-2350 6250);
WIRE 16 -1 (-2350 6350)(-2925 6350);
WIRE 16 -1 (-2225 5600)(-2225 6350);
WIRE 16 -1 (-1925 5600)(-2225 5600);
WIRE 16 -1 (-2225 5550)(-2225 5600);
WIRE 16 -1 (-2925 6250)(-2925 6350);
WIRE 16 -1 (-2925 6350)(-2925 6425);
WIRE 16 -1 (-1925 5550)(-2225 5550);
WIRE 16 -1 (-2225 5550)(-2225 5500);
WIRE 16 -1 (-2225 5500)(-1925 5500);
DOT 1 (-8425 2475);
DOT 1 (-8550 3700);
DOT 1 (-2225 2350);
DOT 1 (-2225 2400);
DOT 1 (-2225 2450);
DOT 1 (-2225 2500);
DOT 1 (-2225 2550);
DOT 1 (-2225 2650);
DOT 1 (-2225 2600);
DOT 1 (-2225 2700);
DOT 1 (-2225 2750);
DOT 1 (-2225 2800);
DOT 1 (-2225 2900);
DOT 1 (-2225 2850);
DOT 1 (-2225 2950);
DOT 1 (-2225 3000);
DOT 1 (-2225 3050);
DOT 1 (-2225 3100);
DOT 1 (-2225 3150);
DOT 1 (-2225 3200);
DOT 1 (-2225 3250);
DOT 1 (-2225 3300);
DOT 1 (-2225 3350);
DOT 1 (-2225 3400);
DOT 1 (-2225 3450);
DOT 1 (-2225 3500);
DOT 1 (-2225 3550);
DOT 1 (-2225 3600);
DOT 1 (-2225 3650);
DOT 1 (-2225 3700);
DOT 1 (-2225 3750);
DOT 1 (-2225 3800);
DOT 1 (-2225 3850);
DOT 1 (-2225 3900);
DOT 1 (-2225 3950);
DOT 1 (-2225 4000);
DOT 1 (-2225 4050);
DOT 1 (-425 2250);
DOT 1 (-425 2300);
DOT 1 (-425 2350);
DOT 1 (-425 2450);
DOT 1 (-425 2500);
DOT 1 (-425 2550);
DOT 1 (-425 2600);
DOT 1 (-425 2650);
DOT 1 (-425 2700);
DOT 1 (-425 2750);
DOT 1 (-425 2800);
DOT 1 (-425 2900);
DOT 1 (-425 2850);
DOT 1 (-425 2950);
DOT 1 (-425 3000);
DOT 1 (-425 3050);
DOT 1 (-425 3100);
DOT 1 (-425 3150);
DOT 1 (-425 3200);
DOT 1 (-425 3250);
DOT 1 (-425 3300);
DOT 1 (-425 3350);
DOT 1 (-425 3400);
DOT 1 (-425 3450);
DOT 1 (-425 3550);
DOT 1 (-425 3500);
DOT 1 (-425 3600);
DOT 1 (-425 3650);
DOT 1 (-425 3700);
DOT 1 (-425 3800);
DOT 1 (-425 3750);
DOT 1 (-425 3850);
DOT 1 (-425 3900);
DOT 1 (-425 3950);
DOT 1 (-425 4050);
DOT 1 (-425 4000);
DOT 1 (-2225 4100);
DOT 1 (-425 4100);
DOT 1 (-2225 4150);
DOT 1 (-2225 4200);
DOT 1 (-2225 4250);
DOT 1 (-2225 4300);
DOT 1 (-2225 4350);
DOT 1 (-2225 4400);
DOT 1 (-2225 4450);
DOT 1 (-2225 4500);
DOT 1 (-2225 4550);
DOT 1 (-2225 4600);
DOT 1 (-2225 4650);
DOT 1 (-2225 4700);
DOT 1 (-2225 4750);
DOT 1 (-2225 4800);
DOT 1 (-2225 4850);
DOT 1 (-2225 4900);
DOT 1 (-2225 4950);
DOT 1 (-2225 5000);
DOT 1 (-2225 5050);
DOT 1 (-2225 5100);
DOT 1 (-2225 5150);
DOT 1 (-2225 5200);
DOT 1 (-2225 5250);
DOT 1 (-2225 5300);
DOT 1 (-2225 5350);
DOT 1 (-2225 5600);
DOT 1 (-2225 5550);
DOT 1 (-425 4150);
DOT 1 (-425 4200);
DOT 1 (-425 4250);
DOT 1 (-425 4300);
DOT 1 (-425 4350);
DOT 1 (-425 4400);
DOT 1 (-425 4450);
DOT 1 (-425 4500);
DOT 1 (-425 4550);
DOT 1 (-425 4600);
DOT 1 (-425 4650);
DOT 1 (-425 4700);
DOT 1 (-425 4750);
DOT 1 (-425 4800);
DOT 1 (-425 4850);
DOT 1 (-425 4900);
DOT 1 (-425 4950);
DOT 1 (-425 5000);
DOT 1 (-425 5050);
DOT 1 (-425 5100);
DOT 1 (-425 5150);
DOT 1 (-425 5200);
DOT 1 (-425 5250);
DOT 1 (-425 5300);
DOT 1 (-425 5350);
DOT 1 (-425 5400);
DOT 1 (-425 5450);
DOT 1 (-425 5500);
DOT 1 (-425 5550);
DOT 1 (-2925 5925);
DOT 1 (-2925 6350);
DOT 1 (-2350 6350);
DOT 1 (-2225 5400);
QUIT
